G04 ================== begin FILE IDENTIFICATION RECORD ==================*
G04 Layout Name:  13919-sa.brd*
G04 Film Name:    NOTICE*
G04 File Format:  Gerber RS274X*
G04 File Origin:  Cadence Allegro 16.5-S039*
G04 Origin Date:  Fri Nov 22 15:27:03 2013*
G04 *
G04 Layer:  MANUFACTURING/THERMAL*
G04 *
G04 Offset:    (0.00 0.00)*
G04 Mirror:    No*
G04 Mode:      Positive*
G04 Rotation:  0*
G04 FullContactRelief:  No*
G04 UndefLineWidth:     6.00*
G04 ================== end FILE IDENTIFICATION RECORD ====================*
%FSLAX35Y35*MOIN*%
%IR0*IPPOS*OFA0.00000B0.00000*MIA0B0*SFA1.00000B1.00000*%
%ADD10C,.006*%
G75*
%LPD*%
G75*
G54D10*
G01X-177767Y-707100D02*
Y161700D01*
G01X1356633Y-707100D02*
X-177767D01*
G01X-148867Y-682600D02*
Y-675800D01*
X-148667Y-675133D01*
X-148267Y-674733D01*
X-147667Y-674600D01*
X-147067Y-674867D01*
X-146767Y-675533D01*
G01X-147967Y-677800D02*
X-149967D01*
G01X-140267Y-682600D02*
X-140867Y-682467D01*
X-141467Y-681933D01*
X-141867Y-681000D01*
X-142067Y-679933D01*
X-141867Y-678867D01*
X-141467Y-677933D01*
X-140867Y-677400D01*
X-140267Y-677267D01*
X-139667Y-677400D01*
X-139067Y-677933D01*
X-138667Y-678867D01*
X-138567Y-679933D01*
X-138667Y-681000D01*
X-139067Y-681933D01*
X-139667Y-682467D01*
X-140267Y-682600D01*
G01X-132267D02*
Y-674600D01*
G01X-124267Y-682600D02*
Y-674600D01*
G01X-116267Y-682600D02*
X-116867Y-682467D01*
X-117467Y-681933D01*
X-117867Y-681000D01*
X-118067Y-679933D01*
X-117867Y-678867D01*
X-117467Y-677933D01*
X-116867Y-677400D01*
X-116267Y-677267D01*
X-115667Y-677400D01*
X-115067Y-677933D01*
X-114667Y-678867D01*
X-114567Y-679933D01*
X-114667Y-681000D01*
X-115067Y-681933D01*
X-115667Y-682467D01*
X-116267Y-682600D01*
G01X-110767Y-677267D02*
X-109567Y-682600D01*
X-108267Y-677267D01*
X-106967Y-682600D01*
X-105767Y-677267D01*
G01X-93667Y-684600D02*
X-92967Y-685133D01*
X-92167Y-685267D01*
X-91467Y-685133D01*
X-90867Y-684467D01*
X-90467Y-683533D01*
Y-677267D01*
G01Y-678333D02*
X-90867Y-677800D01*
X-91467Y-677400D01*
X-92167Y-677267D01*
X-92967Y-677533D01*
X-93467Y-678067D01*
X-93867Y-679000D01*
X-94067Y-679933D01*
X-93967Y-680733D01*
X-93567Y-681667D01*
X-92967Y-682333D01*
X-92167Y-682600D01*
X-91567Y-682467D01*
X-90867Y-681933D01*
X-90467Y-681400D01*
G01X-85767Y-679000D02*
X-82567D01*
X-82867Y-678067D01*
X-83367Y-677533D01*
X-84067Y-677267D01*
X-84767Y-677400D01*
X-85367Y-677800D01*
X-85767Y-678733D01*
X-85967Y-679534D01*
Y-680333D01*
X-85767Y-681133D01*
X-85267Y-681933D01*
X-84667Y-682467D01*
X-83967Y-682600D01*
X-83267Y-682333D01*
X-82567Y-681534D01*
G01X-77667Y-682600D02*
Y-677267D01*
G01Y-678333D02*
X-77167Y-677800D01*
X-76667Y-677400D01*
X-75967Y-677267D01*
X-75467Y-677400D01*
X-74867Y-677800D01*
G01X-70067Y-682600D02*
Y-674600D01*
G01Y-678600D02*
X-69567Y-677800D01*
X-68967Y-677400D01*
X-68367Y-677267D01*
X-67467Y-677533D01*
X-66867Y-678067D01*
X-66467Y-679000D01*
Y-680067D01*
X-66667Y-681133D01*
X-67067Y-681933D01*
X-67767Y-682467D01*
X-68367Y-682600D01*
X-68967Y-682467D01*
X-69567Y-682067D01*
X-70067Y-681400D01*
G01X-61767Y-679000D02*
X-58567D01*
X-58867Y-678067D01*
X-59367Y-677533D01*
X-60067Y-677267D01*
X-60767Y-677400D01*
X-61367Y-677800D01*
X-61767Y-678733D01*
X-61967Y-679534D01*
Y-680333D01*
X-61767Y-681133D01*
X-61267Y-681933D01*
X-60667Y-682467D01*
X-59967Y-682600D01*
X-59267Y-682333D01*
X-58567Y-681534D01*
G01X-53667Y-682600D02*
Y-677267D01*
G01Y-678333D02*
X-53167Y-677800D01*
X-52667Y-677400D01*
X-51967Y-677267D01*
X-51467Y-677400D01*
X-50867Y-677800D01*
G01X-34467Y-674600D02*
Y-682600D01*
G01Y-681400D02*
X-34867Y-682067D01*
X-35467Y-682467D01*
X-36167Y-682600D01*
X-36967Y-682333D01*
X-37567Y-681667D01*
X-37967Y-680867D01*
X-38067Y-679933D01*
X-37967Y-679000D01*
X-37567Y-678200D01*
X-36967Y-677533D01*
X-36167Y-677267D01*
X-35467Y-677400D01*
X-34967Y-677667D01*
X-34467Y-678200D01*
G01X-29767Y-679000D02*
X-26567D01*
X-26867Y-678067D01*
X-27367Y-677533D01*
X-28067Y-677267D01*
X-28767Y-677400D01*
X-29367Y-677800D01*
X-29767Y-678733D01*
X-29967Y-679534D01*
Y-680333D01*
X-29767Y-681133D01*
X-29267Y-681933D01*
X-28667Y-682467D01*
X-27967Y-682600D01*
X-27267Y-682333D01*
X-26567Y-681534D01*
G01X-21767Y-681667D02*
X-21267Y-682200D01*
X-20567Y-682600D01*
X-19967D01*
X-19367Y-682333D01*
X-18967Y-681933D01*
X-18767Y-681400D01*
X-18867Y-680600D01*
X-19267Y-680200D01*
X-21067Y-679400D01*
X-21467Y-678467D01*
X-21267Y-677800D01*
X-20867Y-677400D01*
X-20267Y-677267D01*
X-19667Y-677400D01*
X-19067Y-677800D01*
G01X-12267Y-677267D02*
Y-682600D01*
G01Y-675133D02*
X-12467Y-675000D01*
Y-674733D01*
X-12267Y-674600D01*
X-12067Y-674733D01*
Y-675000D01*
X-12267Y-675133D01*
G01X-5667Y-684600D02*
X-4967Y-685133D01*
X-4167Y-685267D01*
X-3467Y-685133D01*
X-2867Y-684467D01*
X-2467Y-683533D01*
Y-677267D01*
G01Y-678333D02*
X-2867Y-677800D01*
X-3467Y-677400D01*
X-4167Y-677267D01*
X-4967Y-677533D01*
X-5467Y-678067D01*
X-5867Y-679000D01*
X-6067Y-679933D01*
X-5967Y-680733D01*
X-5567Y-681667D01*
X-4967Y-682333D01*
X-4167Y-682600D01*
X-3567Y-682467D01*
X-2867Y-681933D01*
X-2467Y-681400D01*
G01X2033Y-682600D02*
Y-677267D01*
G01Y-678600D02*
X2433Y-677933D01*
X3033Y-677400D01*
X3833Y-677267D01*
X4533Y-677400D01*
X5133Y-677933D01*
X5433Y-678867D01*
Y-682600D01*
G01X-150167Y-660900D02*
Y-652900D01*
X-146367D01*
G01X-147767Y-656767D02*
X-150167D01*
G01X-140267Y-660900D02*
X-140867Y-660767D01*
X-141467Y-660233D01*
X-141867Y-659300D01*
X-142067Y-658233D01*
X-141867Y-657167D01*
X-141467Y-656233D01*
X-140867Y-655700D01*
X-140267Y-655567D01*
X-139667Y-655700D01*
X-139067Y-656233D01*
X-138667Y-657167D01*
X-138567Y-658233D01*
X-138667Y-659300D01*
X-139067Y-660233D01*
X-139667Y-660767D01*
X-140267Y-660900D01*
G01X-133667D02*
Y-655567D01*
G01Y-656633D02*
X-133167Y-656100D01*
X-132667Y-655700D01*
X-131967Y-655567D01*
X-131467Y-655700D01*
X-130867Y-656100D01*
G01X-118167Y-654233D02*
X-117567Y-653433D01*
X-116867Y-653033D01*
X-116067Y-652900D01*
X-115067Y-653167D01*
X-114367Y-653833D01*
X-114167Y-654633D01*
X-114267Y-655434D01*
X-114667Y-656100D01*
X-116667Y-657433D01*
X-117567Y-658367D01*
X-118167Y-659700D01*
X-118367Y-660900D01*
X-114167D01*
G01X-108467D02*
X-108267Y-659167D01*
X-107967Y-657700D01*
X-107567Y-656367D01*
X-107067Y-654900D01*
X-106267Y-652900D01*
X-110267D01*
G01X-99067Y-660900D02*
Y-652900D01*
X-102767Y-658633D01*
X-97767D01*
G01X-94367Y-660900D02*
X-90167Y-652900D01*
G01X-94367D02*
X-90167Y-660900D01*
G01X-77667Y-662900D02*
X-76967Y-663433D01*
X-76167Y-663567D01*
X-75467Y-663433D01*
X-74867Y-662767D01*
X-74467Y-661833D01*
Y-655567D01*
G01Y-656633D02*
X-74867Y-656100D01*
X-75467Y-655700D01*
X-76167Y-655567D01*
X-76967Y-655833D01*
X-77467Y-656367D01*
X-77867Y-657300D01*
X-78067Y-658233D01*
X-77967Y-659033D01*
X-77567Y-659967D01*
X-76967Y-660633D01*
X-76167Y-660900D01*
X-75567Y-660767D01*
X-74867Y-660233D01*
X-74467Y-659700D01*
G01X-69767Y-657300D02*
X-66567D01*
X-66867Y-656367D01*
X-67367Y-655833D01*
X-68067Y-655567D01*
X-68767Y-655700D01*
X-69367Y-656100D01*
X-69767Y-657033D01*
X-69967Y-657834D01*
Y-658633D01*
X-69767Y-659433D01*
X-69267Y-660233D01*
X-68667Y-660767D01*
X-67967Y-660900D01*
X-67267Y-660633D01*
X-66567Y-659834D01*
G01X-61667Y-660900D02*
Y-655567D01*
G01Y-656633D02*
X-61167Y-656100D01*
X-60667Y-655700D01*
X-59967Y-655567D01*
X-59467Y-655700D01*
X-58867Y-656100D01*
G01X-54067Y-660900D02*
Y-652900D01*
G01Y-656900D02*
X-53567Y-656100D01*
X-52967Y-655700D01*
X-52367Y-655567D01*
X-51467Y-655833D01*
X-50867Y-656367D01*
X-50467Y-657300D01*
Y-658367D01*
X-50667Y-659433D01*
X-51067Y-660233D01*
X-51767Y-660767D01*
X-52367Y-660900D01*
X-52967Y-660767D01*
X-53567Y-660367D01*
X-54067Y-659700D01*
G01X-45767Y-657300D02*
X-42567D01*
X-42867Y-656367D01*
X-43367Y-655833D01*
X-44067Y-655567D01*
X-44767Y-655700D01*
X-45367Y-656100D01*
X-45767Y-657033D01*
X-45967Y-657834D01*
Y-658633D01*
X-45767Y-659433D01*
X-45267Y-660233D01*
X-44667Y-660767D01*
X-43967Y-660900D01*
X-43267Y-660633D01*
X-42567Y-659834D01*
G01X-37667Y-660900D02*
Y-655567D01*
G01Y-656633D02*
X-37167Y-656100D01*
X-36667Y-655700D01*
X-35967Y-655567D01*
X-35467Y-655700D01*
X-34867Y-656100D01*
G01X-20867Y-660900D02*
Y-654100D01*
X-20667Y-653433D01*
X-20267Y-653033D01*
X-19667Y-652900D01*
X-19067Y-653167D01*
X-18767Y-653833D01*
G01X-19967Y-656100D02*
X-21967D01*
G01X-12267Y-660900D02*
X-12867Y-660767D01*
X-13467Y-660233D01*
X-13867Y-659300D01*
X-14067Y-658233D01*
X-13867Y-657167D01*
X-13467Y-656233D01*
X-12867Y-655700D01*
X-12267Y-655567D01*
X-11667Y-655700D01*
X-11067Y-656233D01*
X-10667Y-657167D01*
X-10567Y-658233D01*
X-10667Y-659300D01*
X-11067Y-660233D01*
X-11667Y-660767D01*
X-12267Y-660900D01*
G01X-5667D02*
Y-655567D01*
G01Y-656633D02*
X-5167Y-656100D01*
X-4667Y-655700D01*
X-3967Y-655567D01*
X-3467Y-655700D01*
X-2867Y-656100D01*
G01X733Y-660900D02*
Y-655567D01*
G01Y-657033D02*
X1033Y-656367D01*
X1533Y-655833D01*
X2233Y-655567D01*
X2933Y-655833D01*
X3433Y-656367D01*
X3733Y-657033D01*
Y-660900D01*
G01Y-657033D02*
X4033Y-656367D01*
X4533Y-655833D01*
X5233Y-655567D01*
X5933Y-655833D01*
X6433Y-656367D01*
X6733Y-657167D01*
Y-660900D01*
G01X13533D02*
Y-655567D01*
G01Y-656500D02*
X13133Y-655967D01*
X12533Y-655700D01*
X11833Y-655567D01*
X11133Y-655833D01*
X10533Y-656367D01*
X10133Y-657167D01*
X9933Y-658233D01*
X10133Y-659300D01*
X10533Y-660100D01*
X11133Y-660633D01*
X11833Y-660900D01*
X12533Y-660767D01*
X13133Y-660367D01*
X13533Y-659834D01*
G01X19733Y-652900D02*
Y-660900D01*
G01X18333Y-655567D02*
X21133D01*
G01X35733Y-652900D02*
Y-660900D01*
G01X34333Y-655567D02*
X37133D01*
G01X42033Y-660900D02*
Y-652900D01*
G01Y-656767D02*
X42533Y-656100D01*
X43033Y-655700D01*
X43833Y-655567D01*
X44433Y-655700D01*
X45133Y-656233D01*
X45433Y-657033D01*
Y-660900D01*
G01X50233Y-657300D02*
X53433D01*
X53133Y-656367D01*
X52633Y-655833D01*
X51933Y-655567D01*
X51233Y-655700D01*
X50633Y-656100D01*
X50233Y-657033D01*
X50033Y-657834D01*
Y-658633D01*
X50233Y-659433D01*
X50733Y-660233D01*
X51333Y-660767D01*
X52033Y-660900D01*
X52733Y-660633D01*
X53433Y-659834D01*
G01X58333Y-660900D02*
Y-655567D01*
G01Y-656633D02*
X58833Y-656100D01*
X59333Y-655700D01*
X60033Y-655567D01*
X60533Y-655700D01*
X61133Y-656100D01*
G01X64733Y-660900D02*
Y-655567D01*
G01Y-657033D02*
X65033Y-656367D01*
X65533Y-655833D01*
X66233Y-655567D01*
X66933Y-655833D01*
X67433Y-656367D01*
X67733Y-657033D01*
Y-660900D01*
G01Y-657033D02*
X68033Y-656367D01*
X68533Y-655833D01*
X69233Y-655567D01*
X69933Y-655833D01*
X70433Y-656367D01*
X70733Y-657167D01*
Y-660900D01*
G01X77533D02*
Y-655567D01*
G01Y-656500D02*
X77133Y-655967D01*
X76533Y-655700D01*
X75833Y-655567D01*
X75133Y-655833D01*
X74533Y-656367D01*
X74133Y-657167D01*
X73933Y-658233D01*
X74133Y-659300D01*
X74533Y-660100D01*
X75133Y-660633D01*
X75833Y-660900D01*
X76533Y-660767D01*
X77133Y-660367D01*
X77533Y-659834D01*
G01X83733Y-660900D02*
Y-652900D01*
G01X98333Y-660900D02*
Y-655567D01*
G01Y-656633D02*
X98833Y-656100D01*
X99333Y-655700D01*
X100033Y-655567D01*
X100533Y-655700D01*
X101133Y-656100D01*
G01X106233Y-657300D02*
X109433D01*
X109133Y-656367D01*
X108633Y-655833D01*
X107933Y-655567D01*
X107233Y-655700D01*
X106633Y-656100D01*
X106233Y-657033D01*
X106033Y-657834D01*
Y-658633D01*
X106233Y-659433D01*
X106733Y-660233D01*
X107333Y-660767D01*
X108033Y-660900D01*
X108733Y-660633D01*
X109433Y-659834D01*
G01X115733Y-660900D02*
Y-652900D01*
G01X123733Y-655567D02*
Y-660900D01*
G01Y-653433D02*
X123533Y-653300D01*
Y-653033D01*
X123733Y-652900D01*
X123933Y-653033D01*
Y-653300D01*
X123733Y-653433D01*
G01X130233Y-657300D02*
X133433D01*
X133133Y-656367D01*
X132633Y-655833D01*
X131933Y-655567D01*
X131233Y-655700D01*
X130633Y-656100D01*
X130233Y-657033D01*
X130033Y-657834D01*
Y-658633D01*
X130233Y-659433D01*
X130733Y-660233D01*
X131333Y-660767D01*
X132033Y-660900D01*
X132733Y-660633D01*
X133433Y-659834D01*
G01X139133Y-660900D02*
Y-654100D01*
X139333Y-653433D01*
X139733Y-653033D01*
X140333Y-652900D01*
X140933Y-653167D01*
X141233Y-653833D01*
G01X140033Y-656100D02*
X138033D01*
G01X-139267Y-228700D02*
Y-221900D01*
X-139067Y-221233D01*
X-138667Y-220833D01*
X-138067Y-220700D01*
X-137467Y-220967D01*
X-137167Y-221633D01*
G01X-138367Y-223900D02*
X-140367D01*
G01X-130667Y-228700D02*
X-131267Y-228567D01*
X-131867Y-228033D01*
X-132267Y-227100D01*
X-132467Y-226033D01*
X-132267Y-224967D01*
X-131867Y-224033D01*
X-131267Y-223500D01*
X-130667Y-223367D01*
X-130067Y-223500D01*
X-129467Y-224033D01*
X-129067Y-224967D01*
X-128967Y-226033D01*
X-129067Y-227100D01*
X-129467Y-228033D01*
X-130067Y-228567D01*
X-130667Y-228700D01*
G01X-122667D02*
Y-220700D01*
G01X-114667Y-228700D02*
Y-220700D01*
G01X-106667Y-228700D02*
X-107267Y-228567D01*
X-107867Y-228033D01*
X-108267Y-227100D01*
X-108467Y-226033D01*
X-108267Y-224967D01*
X-107867Y-224033D01*
X-107267Y-223500D01*
X-106667Y-223367D01*
X-106067Y-223500D01*
X-105467Y-224033D01*
X-105067Y-224967D01*
X-104967Y-226033D01*
X-105067Y-227100D01*
X-105467Y-228033D01*
X-106067Y-228567D01*
X-106667Y-228700D01*
G01X-101167Y-223367D02*
X-99967Y-228700D01*
X-98667Y-223367D01*
X-97367Y-228700D01*
X-96167Y-223367D01*
G01X-84067Y-230700D02*
X-83367Y-231233D01*
X-82567Y-231367D01*
X-81867Y-231233D01*
X-81267Y-230567D01*
X-80867Y-229633D01*
Y-223367D01*
G01Y-224433D02*
X-81267Y-223900D01*
X-81867Y-223500D01*
X-82567Y-223367D01*
X-83367Y-223633D01*
X-83867Y-224167D01*
X-84267Y-225100D01*
X-84467Y-226033D01*
X-84367Y-226833D01*
X-83967Y-227767D01*
X-83367Y-228433D01*
X-82567Y-228700D01*
X-81967Y-228567D01*
X-81267Y-228033D01*
X-80867Y-227500D01*
G01X-76167Y-225100D02*
X-72967D01*
X-73267Y-224167D01*
X-73767Y-223633D01*
X-74467Y-223367D01*
X-75167Y-223500D01*
X-75767Y-223900D01*
X-76167Y-224833D01*
X-76367Y-225634D01*
Y-226433D01*
X-76167Y-227233D01*
X-75667Y-228033D01*
X-75067Y-228567D01*
X-74367Y-228700D01*
X-73667Y-228433D01*
X-72967Y-227634D01*
G01X-68067Y-228700D02*
Y-223367D01*
G01Y-224433D02*
X-67567Y-223900D01*
X-67067Y-223500D01*
X-66367Y-223367D01*
X-65867Y-223500D01*
X-65267Y-223900D01*
G01X-60467Y-228700D02*
Y-220700D01*
G01Y-224700D02*
X-59967Y-223900D01*
X-59367Y-223500D01*
X-58767Y-223367D01*
X-57867Y-223633D01*
X-57267Y-224167D01*
X-56867Y-225100D01*
Y-226167D01*
X-57067Y-227233D01*
X-57467Y-228033D01*
X-58167Y-228567D01*
X-58767Y-228700D01*
X-59367Y-228567D01*
X-59967Y-228167D01*
X-60467Y-227500D01*
G01X-52167Y-225100D02*
X-48967D01*
X-49267Y-224167D01*
X-49767Y-223633D01*
X-50467Y-223367D01*
X-51167Y-223500D01*
X-51767Y-223900D01*
X-52167Y-224833D01*
X-52367Y-225634D01*
Y-226433D01*
X-52167Y-227233D01*
X-51667Y-228033D01*
X-51067Y-228567D01*
X-50367Y-228700D01*
X-49667Y-228433D01*
X-48967Y-227634D01*
G01X-44067Y-228700D02*
Y-223367D01*
G01Y-224433D02*
X-43567Y-223900D01*
X-43067Y-223500D01*
X-42367Y-223367D01*
X-41867Y-223500D01*
X-41267Y-223900D01*
G01X-24867Y-220700D02*
Y-228700D01*
G01Y-227500D02*
X-25267Y-228167D01*
X-25867Y-228567D01*
X-26567Y-228700D01*
X-27367Y-228433D01*
X-27967Y-227767D01*
X-28367Y-226967D01*
X-28467Y-226033D01*
X-28367Y-225100D01*
X-27967Y-224300D01*
X-27367Y-223633D01*
X-26567Y-223367D01*
X-25867Y-223500D01*
X-25367Y-223767D01*
X-24867Y-224300D01*
G01X-20167Y-225100D02*
X-16967D01*
X-17267Y-224167D01*
X-17767Y-223633D01*
X-18467Y-223367D01*
X-19167Y-223500D01*
X-19767Y-223900D01*
X-20167Y-224833D01*
X-20367Y-225634D01*
Y-226433D01*
X-20167Y-227233D01*
X-19667Y-228033D01*
X-19067Y-228567D01*
X-18367Y-228700D01*
X-17667Y-228433D01*
X-16967Y-227634D01*
G01X-12167Y-227767D02*
X-11667Y-228300D01*
X-10967Y-228700D01*
X-10367D01*
X-9767Y-228433D01*
X-9367Y-228033D01*
X-9167Y-227500D01*
X-9267Y-226700D01*
X-9667Y-226300D01*
X-11467Y-225500D01*
X-11867Y-224567D01*
X-11667Y-223900D01*
X-11267Y-223500D01*
X-10667Y-223367D01*
X-10067Y-223500D01*
X-9467Y-223900D01*
G01X-2667Y-223367D02*
Y-228700D01*
G01Y-221233D02*
X-2867Y-221100D01*
Y-220833D01*
X-2667Y-220700D01*
X-2467Y-220833D01*
Y-221100D01*
X-2667Y-221233D01*
G01X3933Y-230700D02*
X4633Y-231233D01*
X5433Y-231367D01*
X6133Y-231233D01*
X6733Y-230567D01*
X7133Y-229633D01*
Y-223367D01*
G01Y-224433D02*
X6733Y-223900D01*
X6133Y-223500D01*
X5433Y-223367D01*
X4633Y-223633D01*
X4133Y-224167D01*
X3733Y-225100D01*
X3533Y-226033D01*
X3633Y-226833D01*
X4033Y-227767D01*
X4633Y-228433D01*
X5433Y-228700D01*
X6033Y-228567D01*
X6733Y-228033D01*
X7133Y-227500D01*
G01X11633Y-228700D02*
Y-223367D01*
G01Y-224700D02*
X12033Y-224033D01*
X12633Y-223500D01*
X13433Y-223367D01*
X14133Y-223500D01*
X14733Y-224033D01*
X15033Y-224967D01*
Y-228700D01*
G01X-140567Y-207000D02*
Y-199000D01*
X-136767D01*
G01X-138167Y-202867D02*
X-140567D01*
G01X-130667Y-207000D02*
X-131267Y-206867D01*
X-131867Y-206333D01*
X-132267Y-205400D01*
X-132467Y-204333D01*
X-132267Y-203267D01*
X-131867Y-202333D01*
X-131267Y-201800D01*
X-130667Y-201667D01*
X-130067Y-201800D01*
X-129467Y-202333D01*
X-129067Y-203267D01*
X-128967Y-204333D01*
X-129067Y-205400D01*
X-129467Y-206333D01*
X-130067Y-206867D01*
X-130667Y-207000D01*
G01X-124067D02*
Y-201667D01*
G01Y-202733D02*
X-123567Y-202200D01*
X-123067Y-201800D01*
X-122367Y-201667D01*
X-121867Y-201800D01*
X-121267Y-202200D01*
G01X-108567Y-200333D02*
X-107967Y-199533D01*
X-107267Y-199133D01*
X-106467Y-199000D01*
X-105467Y-199267D01*
X-104767Y-199933D01*
X-104567Y-200733D01*
X-104667Y-201534D01*
X-105067Y-202200D01*
X-107067Y-203533D01*
X-107967Y-204467D01*
X-108567Y-205800D01*
X-108767Y-207000D01*
X-104567D01*
G01X-98867D02*
X-98667Y-205267D01*
X-98367Y-203800D01*
X-97967Y-202467D01*
X-97467Y-201000D01*
X-96667Y-199000D01*
X-100667D01*
G01X-89467Y-207000D02*
Y-199000D01*
X-93167Y-204733D01*
X-88167D01*
G01X-84767Y-207000D02*
X-80567Y-199000D01*
G01X-84767D02*
X-80567Y-207000D01*
G01X-68067Y-209000D02*
X-67367Y-209533D01*
X-66567Y-209667D01*
X-65867Y-209533D01*
X-65267Y-208867D01*
X-64867Y-207933D01*
Y-201667D01*
G01Y-202733D02*
X-65267Y-202200D01*
X-65867Y-201800D01*
X-66567Y-201667D01*
X-67367Y-201933D01*
X-67867Y-202467D01*
X-68267Y-203400D01*
X-68467Y-204333D01*
X-68367Y-205133D01*
X-67967Y-206067D01*
X-67367Y-206733D01*
X-66567Y-207000D01*
X-65967Y-206867D01*
X-65267Y-206333D01*
X-64867Y-205800D01*
G01X-60167Y-203400D02*
X-56967D01*
X-57267Y-202467D01*
X-57767Y-201933D01*
X-58467Y-201667D01*
X-59167Y-201800D01*
X-59767Y-202200D01*
X-60167Y-203133D01*
X-60367Y-203934D01*
Y-204733D01*
X-60167Y-205533D01*
X-59667Y-206333D01*
X-59067Y-206867D01*
X-58367Y-207000D01*
X-57667Y-206733D01*
X-56967Y-205934D01*
G01X-52067Y-207000D02*
Y-201667D01*
G01Y-202733D02*
X-51567Y-202200D01*
X-51067Y-201800D01*
X-50367Y-201667D01*
X-49867Y-201800D01*
X-49267Y-202200D01*
G01X-44467Y-207000D02*
Y-199000D01*
G01Y-203000D02*
X-43967Y-202200D01*
X-43367Y-201800D01*
X-42767Y-201667D01*
X-41867Y-201933D01*
X-41267Y-202467D01*
X-40867Y-203400D01*
Y-204467D01*
X-41067Y-205533D01*
X-41467Y-206333D01*
X-42167Y-206867D01*
X-42767Y-207000D01*
X-43367Y-206867D01*
X-43967Y-206467D01*
X-44467Y-205800D01*
G01X-36167Y-203400D02*
X-32967D01*
X-33267Y-202467D01*
X-33767Y-201933D01*
X-34467Y-201667D01*
X-35167Y-201800D01*
X-35767Y-202200D01*
X-36167Y-203133D01*
X-36367Y-203934D01*
Y-204733D01*
X-36167Y-205533D01*
X-35667Y-206333D01*
X-35067Y-206867D01*
X-34367Y-207000D01*
X-33667Y-206733D01*
X-32967Y-205934D01*
G01X-28067Y-207000D02*
Y-201667D01*
G01Y-202733D02*
X-27567Y-202200D01*
X-27067Y-201800D01*
X-26367Y-201667D01*
X-25867Y-201800D01*
X-25267Y-202200D01*
G01X-11267Y-207000D02*
Y-200200D01*
X-11067Y-199533D01*
X-10667Y-199133D01*
X-10067Y-199000D01*
X-9467Y-199267D01*
X-9167Y-199933D01*
G01X-10367Y-202200D02*
X-12367D01*
G01X-2667Y-207000D02*
X-3267Y-206867D01*
X-3867Y-206333D01*
X-4267Y-205400D01*
X-4467Y-204333D01*
X-4267Y-203267D01*
X-3867Y-202333D01*
X-3267Y-201800D01*
X-2667Y-201667D01*
X-2067Y-201800D01*
X-1467Y-202333D01*
X-1067Y-203267D01*
X-967Y-204333D01*
X-1067Y-205400D01*
X-1467Y-206333D01*
X-2067Y-206867D01*
X-2667Y-207000D01*
G01X3933D02*
Y-201667D01*
G01Y-202733D02*
X4433Y-202200D01*
X4933Y-201800D01*
X5633Y-201667D01*
X6133Y-201800D01*
X6733Y-202200D01*
G01X10333Y-207000D02*
Y-201667D01*
G01Y-203133D02*
X10633Y-202467D01*
X11133Y-201933D01*
X11833Y-201667D01*
X12533Y-201933D01*
X13033Y-202467D01*
X13333Y-203133D01*
Y-207000D01*
G01Y-203133D02*
X13633Y-202467D01*
X14133Y-201933D01*
X14833Y-201667D01*
X15533Y-201933D01*
X16033Y-202467D01*
X16333Y-203267D01*
Y-207000D01*
G01X23133D02*
Y-201667D01*
G01Y-202600D02*
X22733Y-202067D01*
X22133Y-201800D01*
X21433Y-201667D01*
X20733Y-201933D01*
X20133Y-202467D01*
X19733Y-203267D01*
X19533Y-204333D01*
X19733Y-205400D01*
X20133Y-206200D01*
X20733Y-206733D01*
X21433Y-207000D01*
X22133Y-206867D01*
X22733Y-206467D01*
X23133Y-205934D01*
G01X29333Y-199000D02*
Y-207000D01*
G01X27933Y-201667D02*
X30733D01*
G01X45333Y-199000D02*
Y-207000D01*
G01X43933Y-201667D02*
X46733D01*
G01X51633Y-207000D02*
Y-199000D01*
G01Y-202867D02*
X52133Y-202200D01*
X52633Y-201800D01*
X53433Y-201667D01*
X54033Y-201800D01*
X54733Y-202333D01*
X55033Y-203133D01*
Y-207000D01*
G01X59833Y-203400D02*
X63033D01*
X62733Y-202467D01*
X62233Y-201933D01*
X61533Y-201667D01*
X60833Y-201800D01*
X60233Y-202200D01*
X59833Y-203133D01*
X59633Y-203934D01*
Y-204733D01*
X59833Y-205533D01*
X60333Y-206333D01*
X60933Y-206867D01*
X61633Y-207000D01*
X62333Y-206733D01*
X63033Y-205934D01*
G01X67933Y-207000D02*
Y-201667D01*
G01Y-202733D02*
X68433Y-202200D01*
X68933Y-201800D01*
X69633Y-201667D01*
X70133Y-201800D01*
X70733Y-202200D01*
G01X74333Y-207000D02*
Y-201667D01*
G01Y-203133D02*
X74633Y-202467D01*
X75133Y-201933D01*
X75833Y-201667D01*
X76533Y-201933D01*
X77033Y-202467D01*
X77333Y-203133D01*
Y-207000D01*
G01Y-203133D02*
X77633Y-202467D01*
X78133Y-201933D01*
X78833Y-201667D01*
X79533Y-201933D01*
X80033Y-202467D01*
X80333Y-203267D01*
Y-207000D01*
G01X87133D02*
Y-201667D01*
G01Y-202600D02*
X86733Y-202067D01*
X86133Y-201800D01*
X85433Y-201667D01*
X84733Y-201933D01*
X84133Y-202467D01*
X83733Y-203267D01*
X83533Y-204333D01*
X83733Y-205400D01*
X84133Y-206200D01*
X84733Y-206733D01*
X85433Y-207000D01*
X86133Y-206867D01*
X86733Y-206467D01*
X87133Y-205934D01*
G01X93333Y-207000D02*
Y-199000D01*
G01X107933Y-207000D02*
Y-201667D01*
G01Y-202733D02*
X108433Y-202200D01*
X108933Y-201800D01*
X109633Y-201667D01*
X110133Y-201800D01*
X110733Y-202200D01*
G01X115833Y-203400D02*
X119033D01*
X118733Y-202467D01*
X118233Y-201933D01*
X117533Y-201667D01*
X116833Y-201800D01*
X116233Y-202200D01*
X115833Y-203133D01*
X115633Y-203934D01*
Y-204733D01*
X115833Y-205533D01*
X116333Y-206333D01*
X116933Y-206867D01*
X117633Y-207000D01*
X118333Y-206733D01*
X119033Y-205934D01*
G01X125333Y-207000D02*
Y-199000D01*
G01X133333Y-201667D02*
Y-207000D01*
G01Y-199533D02*
X133133Y-199400D01*
Y-199133D01*
X133333Y-199000D01*
X133533Y-199133D01*
Y-199400D01*
X133333Y-199533D01*
G01X139833Y-203400D02*
X143033D01*
X142733Y-202467D01*
X142233Y-201933D01*
X141533Y-201667D01*
X140833Y-201800D01*
X140233Y-202200D01*
X139833Y-203133D01*
X139633Y-203934D01*
Y-204733D01*
X139833Y-205533D01*
X140333Y-206333D01*
X140933Y-206867D01*
X141633Y-207000D01*
X142333Y-206733D01*
X143033Y-205934D01*
G01X148733Y-207000D02*
Y-200200D01*
X148933Y-199533D01*
X149333Y-199133D01*
X149933Y-199000D01*
X150533Y-199267D01*
X150833Y-199933D01*
G01X149633Y-202200D02*
X147633D01*
G01X-177767Y-256700D02*
X1356633D01*
G01X-177767Y161700D02*
X1356633D01*
G01X-11867Y-627800D02*
X-15867D01*
Y-619800D01*
X-11867D01*
G01X-13467Y-623667D02*
X-15867D01*
G01X-7967Y-627800D02*
X-3767Y-619800D01*
G01X-7967D02*
X-3767Y-627800D01*
G01X2133Y-628067D02*
X1933Y-627933D01*
Y-627667D01*
X2133Y-627533D01*
X2333Y-627667D01*
Y-627933D01*
X2133Y-628067D01*
G01Y-624467D02*
X1933Y-624333D01*
Y-624067D01*
X2133Y-623933D01*
X2333Y-624067D01*
Y-624333D01*
X2133Y-624467D01*
G01X16233Y-627800D02*
Y-619800D01*
X20033D01*
G01X18633Y-623667D02*
X16233D01*
G01X24133Y-619800D02*
Y-627800D01*
X28133D01*
G01X31633D02*
X34133Y-619800D01*
X36633Y-627800D01*
G01X35733Y-625000D02*
X32533D01*
G01X40033Y-626734D02*
X40833Y-627400D01*
X41733Y-627800D01*
X42533D01*
X43333Y-627400D01*
X43933Y-626734D01*
X44233Y-625800D01*
X44033Y-624867D01*
X43533Y-624067D01*
X42633Y-623533D01*
X41433Y-623267D01*
X40733Y-622733D01*
X40433Y-621800D01*
X40633Y-620867D01*
X41133Y-620200D01*
X41833Y-619800D01*
X42533D01*
X43233Y-620067D01*
X43833Y-620733D01*
G01X48033Y-627800D02*
Y-619800D01*
G01X52233D02*
Y-627800D01*
G01Y-623800D02*
X48033D01*
G01X66133Y-619800D02*
Y-627800D01*
G01X63833Y-619800D02*
X68433D01*
G01X72133Y-627800D02*
Y-619800D01*
X74633D01*
X75433Y-620200D01*
X75933Y-620733D01*
X76133Y-621800D01*
X75933Y-622867D01*
X75333Y-623533D01*
X74633Y-623933D01*
X72133D01*
G01X74633D02*
X76133Y-627800D01*
G01X80233Y-624467D02*
X80933Y-623533D01*
X81533Y-623000D01*
X82333Y-622733D01*
X83033Y-623000D01*
X83533Y-623533D01*
X83933Y-624333D01*
X84033Y-625267D01*
X83933Y-626067D01*
X83533Y-626867D01*
X82933Y-627533D01*
X82233Y-627800D01*
X81433Y-627533D01*
X80733Y-626734D01*
X80333Y-625533D01*
X80233Y-624200D01*
X80433Y-622467D01*
X80733Y-621533D01*
X81233Y-620600D01*
X81933Y-619933D01*
X82633Y-619800D01*
X83333Y-620067D01*
X83833Y-620733D01*
G01X90133Y-619800D02*
X89333Y-620067D01*
X88733Y-620733D01*
X88333Y-621533D01*
X88033Y-622600D01*
X87933Y-623800D01*
X88033Y-625000D01*
X88333Y-626067D01*
X88733Y-626867D01*
X89333Y-627533D01*
X90133Y-627800D01*
X90933Y-627533D01*
X91533Y-626867D01*
X91933Y-626067D01*
X92233Y-625000D01*
X92333Y-623800D01*
X92233Y-622600D01*
X91933Y-621533D01*
X91533Y-620733D01*
X90933Y-620067D01*
X90133Y-619800D01*
G01X96033Y-627800D02*
X100233Y-619800D01*
G01X96033D02*
X100233Y-627800D01*
G01X106133D02*
Y-619800D01*
X104933Y-621400D01*
G01Y-627800D02*
X107333D01*
G01X114133D02*
Y-619800D01*
X112933Y-621400D01*
G01Y-627800D02*
X115333D01*
G01X120433Y-626867D02*
X121133Y-627533D01*
X121933Y-627800D01*
X122733Y-627533D01*
X123433Y-626734D01*
X123933Y-625533D01*
X124133Y-624333D01*
Y-622867D01*
X123933Y-621667D01*
X123433Y-620600D01*
X122833Y-620067D01*
X122133Y-619800D01*
X121333Y-620067D01*
X120733Y-620600D01*
X120333Y-621400D01*
X120133Y-622467D01*
X120333Y-623400D01*
X120833Y-624333D01*
X121433Y-624867D01*
X122133Y-625000D01*
X122933Y-624734D01*
X123533Y-624067D01*
X124133Y-622867D01*
G01X127133Y-630467D02*
X133133D01*
G01X136233Y-621133D02*
X136833Y-620333D01*
X137533Y-619933D01*
X138333Y-619800D01*
X139333Y-620067D01*
X140033Y-620733D01*
X140233Y-621533D01*
X140133Y-622334D01*
X139733Y-623000D01*
X137733Y-624333D01*
X136833Y-625267D01*
X136233Y-626600D01*
X136033Y-627800D01*
X140233D01*
G01X146133Y-619800D02*
X145333Y-620067D01*
X144733Y-620733D01*
X144333Y-621533D01*
X144033Y-622600D01*
X143933Y-623800D01*
X144033Y-625000D01*
X144333Y-626067D01*
X144733Y-626867D01*
X145333Y-627533D01*
X146133Y-627800D01*
X146933Y-627533D01*
X147533Y-626867D01*
X147933Y-626067D01*
X148233Y-625000D01*
X148333Y-623800D01*
X148233Y-622600D01*
X147933Y-621533D01*
X147533Y-620733D01*
X146933Y-620067D01*
X146133Y-619800D01*
G01X152033Y-627800D02*
X156233Y-619800D01*
G01X152033D02*
X156233Y-627800D01*
G01X159933Y-626200D02*
X160533Y-627133D01*
X161333Y-627667D01*
X162233Y-627800D01*
X163033Y-627667D01*
X163833Y-627000D01*
X164333Y-626200D01*
X164433Y-625400D01*
X164233Y-624467D01*
X163533Y-623800D01*
X162833Y-623533D01*
X161933D01*
G01X162833D02*
X163433Y-623133D01*
X163933Y-622467D01*
X164133Y-621667D01*
X163933Y-620867D01*
X163433Y-620200D01*
X162533Y-619800D01*
X161633Y-619933D01*
X160733Y-620467D01*
G01X170133Y-619800D02*
X169333Y-620067D01*
X168733Y-620733D01*
X168333Y-621533D01*
X168033Y-622600D01*
X167933Y-623800D01*
X168033Y-625000D01*
X168333Y-626067D01*
X168733Y-626867D01*
X169333Y-627533D01*
X170133Y-627800D01*
X170933Y-627533D01*
X171533Y-626867D01*
X171933Y-626067D01*
X172233Y-625000D01*
X172333Y-623800D01*
X172233Y-622600D01*
X171933Y-621533D01*
X171533Y-620733D01*
X170933Y-620067D01*
X170133Y-619800D01*
G01X-19367Y-578000D02*
Y-570000D01*
X-14767Y-578000D01*
Y-570000D01*
G01X-11567Y-578000D02*
X-9067Y-570000D01*
X-6567Y-578000D01*
G01X-7467Y-575200D02*
X-10667D01*
G01X-3667Y-578000D02*
Y-570000D01*
X-1067Y-576667D01*
X1533Y-570000D01*
Y-578000D01*
G01X8933D02*
X4933D01*
Y-570000D01*
X8933D01*
G01X7333Y-573867D02*
X4933D01*
G01X14933Y-578267D02*
X14733Y-578133D01*
Y-577867D01*
X14933Y-577733D01*
X15133Y-577867D01*
Y-578133D01*
X14933Y-578267D01*
G01Y-574667D02*
X14733Y-574533D01*
Y-574267D01*
X14933Y-574133D01*
X15133Y-574267D01*
Y-574533D01*
X14933Y-574667D01*
G01X30933Y-570000D02*
Y-578000D01*
G01X28633Y-570000D02*
X33233D01*
G01X36933Y-578000D02*
Y-570000D01*
X39433D01*
X40233Y-570400D01*
X40733Y-570933D01*
X40933Y-572000D01*
X40733Y-573067D01*
X40133Y-573733D01*
X39433Y-574133D01*
X36933D01*
G01X39433D02*
X40933Y-578000D01*
G01X44433D02*
X46933Y-570000D01*
X49433Y-578000D01*
G01X48533Y-575200D02*
X45333D01*
G01X52833Y-578000D02*
X57033Y-570000D01*
G01X52833D02*
X57033Y-578000D01*
G01X63733Y-573733D02*
X64133Y-573333D01*
X64433Y-572667D01*
X64633Y-571733D01*
X64433Y-570933D01*
X64033Y-570400D01*
X63333Y-570000D01*
X60633D01*
Y-578000D01*
X63933D01*
X64633Y-577467D01*
X65033Y-576667D01*
X65233Y-575733D01*
X65033Y-574800D01*
X64433Y-574000D01*
X63733Y-573733D01*
X60633D01*
G01X67933Y-580667D02*
X73933D01*
G01X81133Y-570667D02*
X80533Y-570267D01*
X79833Y-570000D01*
X79033D01*
X78133Y-570400D01*
X77433Y-571067D01*
X76933Y-571867D01*
X76533Y-573200D01*
X76433Y-574400D01*
X76633Y-575600D01*
X76933Y-576400D01*
X77533Y-577200D01*
X78233Y-577733D01*
X78933Y-578000D01*
X79633D01*
X80333Y-577733D01*
X80933Y-577333D01*
X81433Y-576800D01*
G01X84833Y-578000D02*
X89033Y-570000D01*
G01X84833D02*
X89033Y-578000D01*
G01X92733D02*
Y-570000D01*
X94733D01*
X95533Y-570400D01*
X96133Y-570933D01*
X96633Y-571733D01*
X97033Y-572667D01*
X97133Y-574000D01*
X97033Y-575333D01*
X96633Y-576267D01*
X96133Y-577067D01*
X95533Y-577600D01*
X94733Y-578000D01*
X92733D01*
G01X-14067Y-448700D02*
X-14167Y-448600D01*
G01X45733Y-448700D02*
X-14067D01*
G01X45633Y-409200D02*
X-14267D01*
G01X-68167Y-107100D02*
X-72167D01*
Y-99100D01*
X-68167D01*
G01X-69767Y-102967D02*
X-72167D01*
G01X-64267Y-107100D02*
X-60067Y-99100D01*
G01X-64267D02*
X-60067Y-107100D01*
G01X-54167Y-107367D02*
X-54367Y-107233D01*
Y-106967D01*
X-54167Y-106833D01*
X-53967Y-106967D01*
Y-107233D01*
X-54167Y-107367D01*
G01Y-103767D02*
X-54367Y-103633D01*
Y-103367D01*
X-54167Y-103233D01*
X-53967Y-103367D01*
Y-103633D01*
X-54167Y-103767D01*
G01X-40067Y-107100D02*
Y-99100D01*
X-36267D01*
G01X-37667Y-102967D02*
X-40067D01*
G01X-32167Y-99100D02*
Y-107100D01*
X-28167D01*
G01X-24667D02*
X-22167Y-99100D01*
X-19667Y-107100D01*
G01X-20567Y-104300D02*
X-23767D01*
G01X-16267Y-106034D02*
X-15467Y-106700D01*
X-14567Y-107100D01*
X-13767D01*
X-12967Y-106700D01*
X-12367Y-106034D01*
X-12067Y-105100D01*
X-12267Y-104167D01*
X-12767Y-103367D01*
X-13667Y-102833D01*
X-14867Y-102567D01*
X-15567Y-102033D01*
X-15867Y-101100D01*
X-15667Y-100167D01*
X-15167Y-99500D01*
X-14467Y-99100D01*
X-13767D01*
X-13067Y-99367D01*
X-12467Y-100033D01*
G01X-8267Y-107100D02*
Y-99100D01*
G01X-4067D02*
Y-107100D01*
G01Y-103100D02*
X-8267D01*
G01X9833Y-99100D02*
Y-107100D01*
G01X7533Y-99100D02*
X12133D01*
G01X15833Y-107100D02*
Y-99100D01*
X18333D01*
X19133Y-99500D01*
X19633Y-100033D01*
X19833Y-101100D01*
X19633Y-102167D01*
X19033Y-102833D01*
X18333Y-103233D01*
X15833D01*
G01X18333D02*
X19833Y-107100D01*
G01X25833D02*
Y-99100D01*
X24633Y-100700D01*
G01Y-107100D02*
X27033D01*
G01X33833Y-99100D02*
X33033Y-99367D01*
X32433Y-100033D01*
X32033Y-100833D01*
X31733Y-101900D01*
X31633Y-103100D01*
X31733Y-104300D01*
X32033Y-105367D01*
X32433Y-106167D01*
X33033Y-106833D01*
X33833Y-107100D01*
X34633Y-106833D01*
X35233Y-106167D01*
X35633Y-105367D01*
X35933Y-104300D01*
X36033Y-103100D01*
X35933Y-101900D01*
X35633Y-100833D01*
X35233Y-100033D01*
X34633Y-99367D01*
X33833Y-99100D01*
G01X39633Y-105500D02*
X40233Y-106433D01*
X41033Y-106967D01*
X41933Y-107100D01*
X42733Y-106967D01*
X43533Y-106300D01*
X44033Y-105500D01*
X44133Y-104700D01*
X43933Y-103767D01*
X43233Y-103100D01*
X42533Y-102833D01*
X41633D01*
G01X42533D02*
X43133Y-102433D01*
X43633Y-101767D01*
X43833Y-100967D01*
X43633Y-100167D01*
X43133Y-99500D01*
X42233Y-99100D01*
X41333Y-99233D01*
X40433Y-99767D01*
G01X46833Y-109767D02*
X52833D01*
G01X56133Y-106167D02*
X56833Y-106833D01*
X57633Y-107100D01*
X58433Y-106833D01*
X59133Y-106034D01*
X59633Y-104833D01*
X59833Y-103633D01*
Y-102167D01*
X59633Y-100967D01*
X59133Y-99900D01*
X58533Y-99367D01*
X57833Y-99100D01*
X57033Y-99367D01*
X56433Y-99900D01*
X56033Y-100700D01*
X55833Y-101767D01*
X56033Y-102700D01*
X56533Y-103633D01*
X57133Y-104167D01*
X57833Y-104300D01*
X58633Y-104034D01*
X59233Y-103367D01*
X59833Y-102167D01*
G01X63633Y-105500D02*
X64233Y-106433D01*
X65033Y-106967D01*
X65933Y-107100D01*
X66733Y-106967D01*
X67533Y-106300D01*
X68033Y-105500D01*
X68133Y-104700D01*
X67933Y-103767D01*
X67233Y-103100D01*
X66533Y-102833D01*
X65633D01*
G01X66533D02*
X67133Y-102433D01*
X67633Y-101767D01*
X67833Y-100967D01*
X67633Y-100167D01*
X67133Y-99500D01*
X66233Y-99100D01*
X65333Y-99233D01*
X64433Y-99767D01*
G01X70833Y-109767D02*
X76833D01*
G01X79633Y-105500D02*
X80233Y-106433D01*
X81033Y-106967D01*
X81933Y-107100D01*
X82733Y-106967D01*
X83533Y-106300D01*
X84033Y-105500D01*
X84133Y-104700D01*
X83933Y-103767D01*
X83233Y-103100D01*
X82533Y-102833D01*
X81633D01*
G01X82533D02*
X83133Y-102433D01*
X83633Y-101767D01*
X83833Y-100967D01*
X83633Y-100167D01*
X83133Y-99500D01*
X82233Y-99100D01*
X81333Y-99233D01*
X80433Y-99767D01*
G01X89833Y-99100D02*
X89033Y-99367D01*
X88433Y-100033D01*
X88033Y-100833D01*
X87733Y-101900D01*
X87633Y-103100D01*
X87733Y-104300D01*
X88033Y-105367D01*
X88433Y-106167D01*
X89033Y-106833D01*
X89833Y-107100D01*
X90633Y-106833D01*
X91233Y-106167D01*
X91633Y-105367D01*
X91933Y-104300D01*
X92033Y-103100D01*
X91933Y-101900D01*
X91633Y-100833D01*
X91233Y-100033D01*
X90633Y-99367D01*
X89833Y-99100D01*
G01X97833Y-107367D02*
X97633Y-107233D01*
Y-106967D01*
X97833Y-106833D01*
X98033Y-106967D01*
Y-107233D01*
X97833Y-107367D01*
G01Y-103767D02*
X97633Y-103633D01*
Y-103367D01*
X97833Y-103233D01*
X98033Y-103367D01*
Y-103633D01*
X97833Y-103767D01*
G01X-58367Y34500D02*
X-57767Y33567D01*
X-56967Y33033D01*
X-56067Y32900D01*
X-55267Y33033D01*
X-54467Y33700D01*
X-53967Y34500D01*
X-53867Y35300D01*
X-54067Y36233D01*
X-54767Y36900D01*
X-55467Y37167D01*
X-56367D01*
G01X-55467D02*
X-54867Y37567D01*
X-54367Y38233D01*
X-54167Y39033D01*
X-54367Y39833D01*
X-54867Y40500D01*
X-55767Y40900D01*
X-56667Y40767D01*
X-57567Y40233D01*
G01X-48167Y32633D02*
X-48367Y32767D01*
Y33033D01*
X-48167Y33167D01*
X-47967Y33033D01*
Y32767D01*
X-48167Y32633D01*
G01X-58067Y55567D02*
X-57467Y56367D01*
X-56767Y56767D01*
X-55967Y56900D01*
X-54967Y56633D01*
X-54267Y55967D01*
X-54067Y55167D01*
X-54167Y54366D01*
X-54567Y53700D01*
X-56567Y52367D01*
X-57467Y51433D01*
X-58067Y50100D01*
X-58267Y48900D01*
X-54067D01*
G01X-48167Y48633D02*
X-48367Y48767D01*
Y49033D01*
X-48167Y49167D01*
X-47967Y49033D01*
Y48767D01*
X-48167Y48633D01*
G01X-56167Y64900D02*
Y72900D01*
X-57367Y71300D01*
G01Y64900D02*
X-54967D01*
G01X-48167Y64633D02*
X-48367Y64767D01*
Y65033D01*
X-48167Y65167D01*
X-47967Y65033D01*
Y64767D01*
X-48167Y64633D01*
G01X-34067Y64900D02*
Y72900D01*
X-30267D01*
G01X-31667Y69033D02*
X-34067D01*
G01X-26167Y72900D02*
Y64900D01*
X-22167D01*
G01X-18667D02*
X-16167Y72900D01*
X-13667Y64900D01*
G01X-14567Y67700D02*
X-17767D01*
G01X-10267Y65966D02*
X-9467Y65300D01*
X-8567Y64900D01*
X-7767D01*
X-6967Y65300D01*
X-6367Y65966D01*
X-6067Y66900D01*
X-6267Y67833D01*
X-6767Y68633D01*
X-7667Y69167D01*
X-8867Y69433D01*
X-9567Y69967D01*
X-9867Y70900D01*
X-9667Y71833D01*
X-9167Y72500D01*
X-8467Y72900D01*
X-7767D01*
X-7067Y72633D01*
X-6467Y71967D01*
G01X-2267Y64900D02*
Y72900D01*
G01X1933D02*
Y64900D01*
G01Y68900D02*
X-2267D01*
G01X15833Y72900D02*
Y64900D01*
G01X13533Y72900D02*
X18133D01*
G01X21733Y64900D02*
Y72900D01*
G01X25933D02*
Y64900D01*
G01Y68900D02*
X21733D01*
G01X29233Y64900D02*
Y72900D01*
X31833Y66233D01*
X34433Y72900D01*
Y64900D01*
G01X37833Y72900D02*
Y64900D01*
X41833D01*
G01X47833D02*
Y72900D01*
X46633Y71300D01*
G01Y64900D02*
X49033D01*
G01X55833Y72900D02*
X55033Y72633D01*
X54433Y71967D01*
X54033Y71167D01*
X53733Y70100D01*
X53633Y68900D01*
X53733Y67700D01*
X54033Y66633D01*
X54433Y65833D01*
X55033Y65167D01*
X55833Y64900D01*
X56633Y65167D01*
X57233Y65833D01*
X57633Y66633D01*
X57933Y67700D01*
X58033Y68900D01*
X57933Y70100D01*
X57633Y71167D01*
X57233Y71967D01*
X56633Y72633D01*
X55833Y72900D01*
G01X71833Y64633D02*
X71633Y64767D01*
Y65033D01*
X71833Y65167D01*
X72033Y65033D01*
Y64767D01*
X71833Y64633D01*
G01Y68233D02*
X71633Y68367D01*
Y68633D01*
X71833Y68767D01*
X72033Y68633D01*
Y68367D01*
X71833Y68233D01*
G01X85933Y64900D02*
Y72900D01*
X89733D01*
G01X88333Y69033D02*
X85933D01*
G01X94133Y70233D02*
Y66500D01*
X94533Y65567D01*
X95133Y65033D01*
X95833Y64900D01*
X96533Y65033D01*
X97133Y65567D01*
X97533Y66500D01*
G01Y64900D02*
Y70233D01*
G01X103833Y64900D02*
Y72900D01*
G01X111833Y64900D02*
Y72900D01*
G01X129433Y69567D02*
X128733Y70100D01*
X128133Y70233D01*
X127333Y69967D01*
X126733Y69433D01*
X126333Y68500D01*
X126233Y67567D01*
X126333Y66633D01*
X126733Y65833D01*
X127333Y65167D01*
X128133Y64900D01*
X128833Y65167D01*
X129433Y65700D01*
G01X135833Y64900D02*
X135233Y65033D01*
X134633Y65567D01*
X134233Y66500D01*
X134033Y67567D01*
X134233Y68633D01*
X134633Y69567D01*
X135233Y70100D01*
X135833Y70233D01*
X136433Y70100D01*
X137033Y69567D01*
X137433Y68633D01*
X137533Y67567D01*
X137433Y66500D01*
X137033Y65567D01*
X136433Y65033D01*
X135833Y64900D01*
G01X142133D02*
Y70233D01*
G01Y68900D02*
X142533Y69567D01*
X143133Y70100D01*
X143933Y70233D01*
X144633Y70100D01*
X145233Y69567D01*
X145533Y68633D01*
Y64900D01*
G01X151833Y72900D02*
Y64900D01*
G01X150433Y70233D02*
X153233D01*
G01X161633Y64900D02*
Y70233D01*
G01Y69300D02*
X161233Y69833D01*
X160633Y70100D01*
X159933Y70233D01*
X159233Y69967D01*
X158633Y69433D01*
X158233Y68633D01*
X158033Y67567D01*
X158233Y66500D01*
X158633Y65700D01*
X159233Y65167D01*
X159933Y64900D01*
X160633Y65033D01*
X161233Y65433D01*
X161633Y65966D01*
G01X169433Y69567D02*
X168733Y70100D01*
X168133Y70233D01*
X167333Y69967D01*
X166733Y69433D01*
X166333Y68500D01*
X166233Y67567D01*
X166333Y66633D01*
X166733Y65833D01*
X167333Y65167D01*
X168133Y64900D01*
X168833Y65167D01*
X169433Y65700D01*
G01X175833Y72900D02*
Y64900D01*
G01X174433Y70233D02*
X177233D01*
G01X-70367Y92900D02*
Y100900D01*
X-68367D01*
X-67567Y100500D01*
X-66967Y99967D01*
X-66467Y99167D01*
X-66067Y98233D01*
X-65967Y96900D01*
X-66067Y95567D01*
X-66467Y94633D01*
X-66967Y93833D01*
X-67567Y93300D01*
X-68367Y92900D01*
X-70367D01*
G01X-61667Y96500D02*
X-58467D01*
X-58767Y97433D01*
X-59267Y97967D01*
X-59967Y98233D01*
X-60667Y98100D01*
X-61267Y97700D01*
X-61667Y96767D01*
X-61867Y95966D01*
Y95167D01*
X-61667Y94367D01*
X-61167Y93567D01*
X-60567Y93033D01*
X-59867Y92900D01*
X-59167Y93167D01*
X-58467Y93966D01*
G01X-52767Y92900D02*
Y99700D01*
X-52567Y100367D01*
X-52167Y100767D01*
X-51567Y100900D01*
X-50967Y100633D01*
X-50667Y99967D01*
G01X-51867Y97700D02*
X-53867D01*
G01X-44167Y98233D02*
Y92900D01*
G01Y100367D02*
X-44367Y100500D01*
Y100767D01*
X-44167Y100900D01*
X-43967Y100767D01*
Y100500D01*
X-44167Y100367D01*
G01X-37867Y92900D02*
Y98233D01*
G01Y96900D02*
X-37467Y97567D01*
X-36867Y98100D01*
X-36067Y98233D01*
X-35367Y98100D01*
X-34767Y97567D01*
X-34467Y96633D01*
Y92900D01*
G01X-29667Y96500D02*
X-26467D01*
X-26767Y97433D01*
X-27267Y97967D01*
X-27967Y98233D01*
X-28667Y98100D01*
X-29267Y97700D01*
X-29667Y96767D01*
X-29867Y95966D01*
Y95167D01*
X-29667Y94367D01*
X-29167Y93567D01*
X-28567Y93033D01*
X-27867Y92900D01*
X-27167Y93167D01*
X-26467Y93966D01*
G01X-12167Y100900D02*
Y92900D01*
G01X-13567Y98233D02*
X-10767D01*
G01X-5867Y92900D02*
Y100900D01*
G01Y97033D02*
X-5367Y97700D01*
X-4867Y98100D01*
X-4067Y98233D01*
X-3467Y98100D01*
X-2767Y97567D01*
X-2467Y96767D01*
Y92900D01*
G01X2333Y96500D02*
X5533D01*
X5233Y97433D01*
X4733Y97967D01*
X4033Y98233D01*
X3333Y98100D01*
X2733Y97700D01*
X2333Y96767D01*
X2133Y95966D01*
Y95167D01*
X2333Y94367D01*
X2833Y93567D01*
X3433Y93033D01*
X4133Y92900D01*
X4833Y93167D01*
X5533Y93966D01*
G01X10433Y92900D02*
Y98233D01*
G01Y97167D02*
X10933Y97700D01*
X11433Y98100D01*
X12133Y98233D01*
X12633Y98100D01*
X13233Y97700D01*
G01X16833Y92900D02*
Y98233D01*
G01Y96767D02*
X17133Y97433D01*
X17633Y97967D01*
X18333Y98233D01*
X19033Y97967D01*
X19533Y97433D01*
X19833Y96767D01*
Y92900D01*
G01Y96767D02*
X20133Y97433D01*
X20633Y97967D01*
X21333Y98233D01*
X22033Y97967D01*
X22533Y97433D01*
X22833Y96633D01*
Y92900D01*
G01X29633D02*
Y98233D01*
G01Y97300D02*
X29233Y97833D01*
X28633Y98100D01*
X27933Y98233D01*
X27233Y97967D01*
X26633Y97433D01*
X26233Y96633D01*
X26033Y95567D01*
X26233Y94500D01*
X26633Y93700D01*
X27233Y93167D01*
X27933Y92900D01*
X28633Y93033D01*
X29233Y93433D01*
X29633Y93966D01*
G01X35833Y92900D02*
Y100900D01*
G01X50433Y92900D02*
Y98233D01*
G01Y97167D02*
X50933Y97700D01*
X51433Y98100D01*
X52133Y98233D01*
X52633Y98100D01*
X53233Y97700D01*
G01X58333Y96500D02*
X61533D01*
X61233Y97433D01*
X60733Y97967D01*
X60033Y98233D01*
X59333Y98100D01*
X58733Y97700D01*
X58333Y96767D01*
X58133Y95966D01*
Y95167D01*
X58333Y94367D01*
X58833Y93567D01*
X59433Y93033D01*
X60133Y92900D01*
X60833Y93167D01*
X61533Y93966D01*
G01X67833Y92900D02*
Y100900D01*
G01X75833Y98233D02*
Y92900D01*
G01Y100367D02*
X75633Y100500D01*
Y100767D01*
X75833Y100900D01*
X76033Y100767D01*
Y100500D01*
X75833Y100367D01*
G01X82333Y96500D02*
X85533D01*
X85233Y97433D01*
X84733Y97967D01*
X84033Y98233D01*
X83333Y98100D01*
X82733Y97700D01*
X82333Y96767D01*
X82133Y95966D01*
Y95167D01*
X82333Y94367D01*
X82833Y93567D01*
X83433Y93033D01*
X84133Y92900D01*
X84833Y93167D01*
X85533Y93966D01*
G01X91233Y92900D02*
Y99700D01*
X91433Y100367D01*
X91833Y100767D01*
X92433Y100900D01*
X93033Y100633D01*
X93333Y99967D01*
G01X92133Y97700D02*
X90133D01*
G01X109433Y97567D02*
X108733Y98100D01*
X108133Y98233D01*
X107333Y97967D01*
X106733Y97433D01*
X106333Y96500D01*
X106233Y95567D01*
X106333Y94633D01*
X106733Y93833D01*
X107333Y93167D01*
X108133Y92900D01*
X108833Y93167D01*
X109433Y93700D01*
G01X115833Y92900D02*
X115233Y93033D01*
X114633Y93567D01*
X114233Y94500D01*
X114033Y95567D01*
X114233Y96633D01*
X114633Y97567D01*
X115233Y98100D01*
X115833Y98233D01*
X116433Y98100D01*
X117033Y97567D01*
X117433Y96633D01*
X117533Y95567D01*
X117433Y94500D01*
X117033Y93567D01*
X116433Y93033D01*
X115833Y92900D01*
G01X122133D02*
Y98233D01*
G01Y96900D02*
X122533Y97567D01*
X123133Y98100D01*
X123933Y98233D01*
X124633Y98100D01*
X125233Y97567D01*
X125533Y96633D01*
Y92900D01*
G01X130133D02*
Y98233D01*
G01Y96900D02*
X130533Y97567D01*
X131133Y98100D01*
X131933Y98233D01*
X132633Y98100D01*
X133233Y97567D01*
X133533Y96633D01*
Y92900D01*
G01X138333Y96500D02*
X141533D01*
X141233Y97433D01*
X140733Y97967D01*
X140033Y98233D01*
X139333Y98100D01*
X138733Y97700D01*
X138333Y96767D01*
X138133Y95966D01*
Y95167D01*
X138333Y94367D01*
X138833Y93567D01*
X139433Y93033D01*
X140133Y92900D01*
X140833Y93167D01*
X141533Y93966D01*
G01X149433Y97567D02*
X148733Y98100D01*
X148133Y98233D01*
X147333Y97967D01*
X146733Y97433D01*
X146333Y96500D01*
X146233Y95567D01*
X146333Y94633D01*
X146733Y93833D01*
X147333Y93167D01*
X148133Y92900D01*
X148833Y93167D01*
X149433Y93700D01*
G01X155833Y100900D02*
Y92900D01*
G01X154433Y98233D02*
X157233D01*
G01X-25167Y54900D02*
X-23767Y46900D01*
X-22167Y54900D01*
X-20567Y46900D01*
X-19167Y54900D01*
G01X-14167Y52233D02*
Y46900D01*
G01Y54367D02*
X-14367Y54500D01*
Y54767D01*
X-14167Y54900D01*
X-13967Y54767D01*
Y54500D01*
X-14167Y54367D01*
G01X-7667Y47833D02*
X-7167Y47300D01*
X-6467Y46900D01*
X-5867D01*
X-5267Y47167D01*
X-4867Y47567D01*
X-4667Y48100D01*
X-4767Y48900D01*
X-5167Y49300D01*
X-6967Y50100D01*
X-7367Y51033D01*
X-7167Y51700D01*
X-6767Y52100D01*
X-6167Y52233D01*
X-5567Y52100D01*
X-4967Y51700D01*
G01X1833Y54900D02*
Y46900D01*
G01X433Y52233D02*
X3233D01*
G01X8433Y46900D02*
Y52233D01*
G01Y51167D02*
X8933Y51700D01*
X9433Y52100D01*
X10133Y52233D01*
X10633Y52100D01*
X11233Y51700D01*
G01X17833Y46900D02*
X17233Y47033D01*
X16633Y47567D01*
X16233Y48500D01*
X16033Y49567D01*
X16233Y50633D01*
X16633Y51567D01*
X17233Y52100D01*
X17833Y52233D01*
X18433Y52100D01*
X19033Y51567D01*
X19433Y50633D01*
X19533Y49567D01*
X19433Y48500D01*
X19033Y47567D01*
X18433Y47033D01*
X17833Y46900D01*
G01X24133D02*
Y52233D01*
G01Y50900D02*
X24533Y51567D01*
X25133Y52100D01*
X25933Y52233D01*
X26633Y52100D01*
X27233Y51567D01*
X27533Y50633D01*
Y46900D01*
G01X41833Y54900D02*
Y46900D01*
G01X39533Y54900D02*
X44133D01*
G01X47733Y46900D02*
Y54900D01*
G01X51933D02*
Y46900D01*
G01Y50900D02*
X47733D01*
G01X55233Y46900D02*
Y54900D01*
X57833Y48233D01*
X60433Y54900D01*
Y46900D01*
G01X63833Y54900D02*
Y46900D01*
X67833D01*
G01X83633Y54900D02*
Y46900D01*
G01Y48100D02*
X83233Y47433D01*
X82633Y47033D01*
X81933Y46900D01*
X81133Y47167D01*
X80533Y47833D01*
X80133Y48633D01*
X80033Y49567D01*
X80133Y50500D01*
X80533Y51300D01*
X81133Y51967D01*
X81933Y52233D01*
X82633Y52100D01*
X83133Y51833D01*
X83633Y51300D01*
G01X88333Y50500D02*
X91533D01*
X91233Y51433D01*
X90733Y51967D01*
X90033Y52233D01*
X89333Y52100D01*
X88733Y51700D01*
X88333Y50767D01*
X88133Y49966D01*
Y49167D01*
X88333Y48367D01*
X88833Y47567D01*
X89433Y47033D01*
X90133Y46900D01*
X90833Y47167D01*
X91533Y47966D01*
G01X97233Y46900D02*
Y53700D01*
X97433Y54367D01*
X97833Y54767D01*
X98433Y54900D01*
X99033Y54633D01*
X99333Y53967D01*
G01X98133Y51700D02*
X96133D01*
G01X107633Y46900D02*
Y52233D01*
G01Y51300D02*
X107233Y51833D01*
X106633Y52100D01*
X105933Y52233D01*
X105233Y51967D01*
X104633Y51433D01*
X104233Y50633D01*
X104033Y49567D01*
X104233Y48500D01*
X104633Y47700D01*
X105233Y47167D01*
X105933Y46900D01*
X106633Y47033D01*
X107233Y47433D01*
X107633Y47966D01*
G01X112133Y52233D02*
Y48500D01*
X112533Y47567D01*
X113133Y47033D01*
X113833Y46900D01*
X114533Y47033D01*
X115133Y47567D01*
X115533Y48500D01*
G01Y46900D02*
Y52233D01*
G01X121833Y46900D02*
Y54900D01*
G01X129833D02*
Y46900D01*
G01X128433Y52233D02*
X131233D01*
G01X145833Y54900D02*
Y46900D01*
G01X144433Y52233D02*
X147233D01*
G01X151733Y44500D02*
X152333Y44233D01*
X153133Y44500D01*
X153633Y45033D01*
X154033Y45700D01*
X154633Y47833D01*
X155933Y52233D01*
G01X152733D02*
X154633Y47833D01*
G01X160033Y44233D02*
Y52233D01*
G01Y51033D02*
X160533Y51700D01*
X161033Y52100D01*
X161833Y52233D01*
X162533Y52100D01*
X163233Y51433D01*
X163533Y50500D01*
X163633Y49567D01*
X163533Y48633D01*
X163233Y47700D01*
X162633Y47167D01*
X161833Y46900D01*
X161133Y47033D01*
X160433Y47433D01*
X160033Y47966D01*
G01X168333Y50500D02*
X171533D01*
X171233Y51433D01*
X170733Y51967D01*
X170033Y52233D01*
X169333Y52100D01*
X168733Y51700D01*
X168333Y50767D01*
X168133Y49966D01*
Y49167D01*
X168333Y48367D01*
X168833Y47567D01*
X169433Y47033D01*
X170133Y46900D01*
X170833Y47167D01*
X171533Y47966D01*
G01X4833Y-601800D02*
X833D01*
Y-593800D01*
X4833D01*
G01X3233Y-597667D02*
X833D01*
G01X10833Y-602067D02*
X10633Y-601933D01*
Y-601667D01*
X10833Y-601533D01*
X11033Y-601667D01*
Y-601933D01*
X10833Y-602067D01*
G01Y-598467D02*
X10633Y-598333D01*
Y-598067D01*
X10833Y-597933D01*
X11033Y-598067D01*
Y-598333D01*
X10833Y-598467D01*
G01X17333Y-512400D02*
X13333D01*
Y-504400D01*
X17333D01*
G01X15733Y-508267D02*
X13333D01*
G01X45833Y-507500D02*
X43933Y-509400D01*
G01X46033Y-514000D02*
X45933Y-514100D01*
G01X46033Y-464800D02*
Y-514000D01*
G01X33733Y-534200D02*
X72633D01*
G01X45833Y-507200D02*
Y-507500D01*
G01X46033Y-507200D02*
X43633Y-504800D01*
G01X45833Y-507400D02*
X46033Y-507200D01*
G01X21233Y-507400D02*
X45833D01*
G01X7933Y-448900D02*
X12033Y-453000D01*
G01X7933Y-448800D02*
Y-448900D01*
G01X7633Y-448600D02*
X3233Y-453000D01*
G01X7733Y-448700D02*
X7633Y-448600D01*
G01X7733Y-469900D02*
Y-448700D01*
G01X46063Y-448785D02*
X51968D01*
G01X46063Y-464533D02*
Y-448785D01*
G01Y-464533D02*
G03X73622Y-502090I39371J0D01*
G01X6833Y-433400D02*
Y-425400D01*
X8833D01*
X9633Y-425800D01*
X10233Y-426333D01*
X10733Y-427133D01*
X11133Y-428067D01*
X11233Y-429400D01*
X11133Y-430733D01*
X10733Y-431667D01*
X10233Y-432467D01*
X9633Y-433000D01*
X8833Y-433400D01*
X6833D01*
G01X8833Y-409200D02*
X11933Y-406100D01*
G01X8733Y-409200D02*
X8833D01*
G01X8733Y-408800D02*
X9133D01*
G01X8533Y-409000D02*
X5533Y-406000D01*
G01X8833Y-408700D02*
X8533Y-409000D01*
G01X8833Y-388900D02*
Y-408700D01*
G01X46033Y-390100D02*
Y-318100D01*
G01X51968Y-409415D02*
X46063D01*
G01X73622Y-356110D02*
G03X46063Y-393667I11812J-37557D01*
G01Y-409415D02*
Y-393667D01*
G01X46333Y-335400D02*
X48133Y-337200D01*
G01X46333Y-335300D02*
Y-335400D01*
G01X46233Y-335100D02*
X48333Y-333000D01*
G01X46433Y-335300D02*
X46233Y-335100D01*
G01X59833Y-335300D02*
X46433D01*
G01X15733Y-311800D02*
X11733D01*
Y-303800D01*
X15733D01*
G01X14133Y-307667D02*
X11733D01*
G01X19733Y-303800D02*
Y-311800D01*
X23733D01*
G01X27733Y-303800D02*
Y-311800D01*
X31733D01*
G01X36533Y-303800D02*
X38933D01*
G01X37733D02*
Y-311800D01*
G01X36533D02*
X38933D01*
G01X43733D02*
Y-303800D01*
X46133D01*
X46933Y-304200D01*
X47533Y-305133D01*
X47733Y-306200D01*
X47533Y-307267D01*
X47033Y-308067D01*
X46133Y-308467D01*
X43733D01*
G01X51633Y-310734D02*
X52433Y-311400D01*
X53333Y-311800D01*
X54133D01*
X54933Y-311400D01*
X55533Y-310734D01*
X55833Y-309800D01*
X55633Y-308867D01*
X55133Y-308067D01*
X54233Y-307533D01*
X53033Y-307267D01*
X52333Y-306733D01*
X52033Y-305800D01*
X52233Y-304867D01*
X52733Y-304200D01*
X53433Y-303800D01*
X54133D01*
X54833Y-304067D01*
X55433Y-304733D01*
G01X63733Y-311800D02*
X59733D01*
Y-303800D01*
X63733D01*
G01X62133Y-307667D02*
X59733D01*
G01X77733Y-303800D02*
Y-311800D01*
G01X75433Y-303800D02*
X80033D01*
G01X84033Y-311800D02*
Y-303800D01*
G01Y-307667D02*
X84533Y-307000D01*
X85033Y-306600D01*
X85833Y-306467D01*
X86433Y-306600D01*
X87133Y-307133D01*
X87433Y-307933D01*
Y-311800D01*
G01X92233Y-308200D02*
X95433D01*
X95133Y-307267D01*
X94633Y-306733D01*
X93933Y-306467D01*
X93233Y-306600D01*
X92633Y-307000D01*
X92233Y-307933D01*
X92033Y-308734D01*
Y-309533D01*
X92233Y-310333D01*
X92733Y-311133D01*
X93333Y-311667D01*
X94033Y-311800D01*
X94733Y-311533D01*
X95433Y-310734D01*
G01X100333Y-311800D02*
Y-306467D01*
G01Y-307533D02*
X100833Y-307000D01*
X101333Y-306600D01*
X102033Y-306467D01*
X102533Y-306600D01*
X103133Y-307000D01*
G01X106733Y-311800D02*
Y-306467D01*
G01Y-307933D02*
X107033Y-307267D01*
X107533Y-306733D01*
X108233Y-306467D01*
X108933Y-306733D01*
X109433Y-307267D01*
X109733Y-307933D01*
Y-311800D01*
G01Y-307933D02*
X110033Y-307267D01*
X110533Y-306733D01*
X111233Y-306467D01*
X111933Y-306733D01*
X112433Y-307267D01*
X112733Y-308067D01*
Y-311800D01*
G01X119533D02*
Y-306467D01*
G01Y-307400D02*
X119133Y-306867D01*
X118533Y-306600D01*
X117833Y-306467D01*
X117133Y-306733D01*
X116533Y-307267D01*
X116133Y-308067D01*
X115933Y-309133D01*
X116133Y-310200D01*
X116533Y-311000D01*
X117133Y-311533D01*
X117833Y-311800D01*
X118533Y-311667D01*
X119133Y-311267D01*
X119533Y-310734D01*
G01X125733Y-311800D02*
Y-303800D01*
G01X16333Y-71900D02*
X18733D01*
G01X17533D02*
Y-79900D01*
G01X16333D02*
X18733D01*
G01X23833D02*
Y-74567D01*
G01Y-75900D02*
X24233Y-75233D01*
X24833Y-74700D01*
X25633Y-74567D01*
X26333Y-74700D01*
X26933Y-75233D01*
X27233Y-76167D01*
Y-79900D01*
G01X31833D02*
Y-74567D01*
G01Y-75900D02*
X32233Y-75233D01*
X32833Y-74700D01*
X33633Y-74567D01*
X34333Y-74700D01*
X34933Y-75233D01*
X35233Y-76167D01*
Y-79900D01*
G01X40033Y-76300D02*
X43233D01*
X42933Y-75367D01*
X42433Y-74833D01*
X41733Y-74567D01*
X41033Y-74700D01*
X40433Y-75100D01*
X40033Y-76033D01*
X39833Y-76834D01*
Y-77633D01*
X40033Y-78433D01*
X40533Y-79233D01*
X41133Y-79767D01*
X41833Y-79900D01*
X42533Y-79633D01*
X43233Y-78834D01*
G01X48133Y-79900D02*
Y-74567D01*
G01Y-75633D02*
X48633Y-75100D01*
X49133Y-74700D01*
X49833Y-74567D01*
X50333Y-74700D01*
X50933Y-75100D01*
G01X63333Y-79900D02*
Y-71900D01*
X65333D01*
X66133Y-72300D01*
X66733Y-72833D01*
X67233Y-73633D01*
X67633Y-74567D01*
X67733Y-75900D01*
X67633Y-77233D01*
X67233Y-78167D01*
X66733Y-78967D01*
X66133Y-79500D01*
X65333Y-79900D01*
X63333D01*
G01X73533Y-74567D02*
Y-79900D01*
G01Y-72433D02*
X73333Y-72300D01*
Y-72033D01*
X73533Y-71900D01*
X73733Y-72033D01*
Y-72300D01*
X73533Y-72433D01*
G01X83333Y-79900D02*
Y-74567D01*
G01Y-75500D02*
X82933Y-74967D01*
X82333Y-74700D01*
X81633Y-74567D01*
X80933Y-74833D01*
X80333Y-75367D01*
X79933Y-76167D01*
X79733Y-77233D01*
X79933Y-78300D01*
X80333Y-79100D01*
X80933Y-79633D01*
X81633Y-79900D01*
X82333Y-79767D01*
X82933Y-79367D01*
X83333Y-78834D01*
G01X86533Y-79900D02*
Y-74567D01*
G01Y-76033D02*
X86833Y-75367D01*
X87333Y-74833D01*
X88033Y-74567D01*
X88733Y-74833D01*
X89233Y-75367D01*
X89533Y-76033D01*
Y-79900D01*
G01Y-76033D02*
X89833Y-75367D01*
X90333Y-74833D01*
X91033Y-74567D01*
X91733Y-74833D01*
X92233Y-75367D01*
X92533Y-76167D01*
Y-79900D01*
G01X96033Y-76300D02*
X99233D01*
X98933Y-75367D01*
X98433Y-74833D01*
X97733Y-74567D01*
X97033Y-74700D01*
X96433Y-75100D01*
X96033Y-76033D01*
X95833Y-76834D01*
Y-77633D01*
X96033Y-78433D01*
X96533Y-79233D01*
X97133Y-79767D01*
X97833Y-79900D01*
X98533Y-79633D01*
X99233Y-78834D01*
G01X105533Y-71900D02*
Y-79900D01*
G01X104133Y-74567D02*
X106933D01*
G01X112033Y-76300D02*
X115233D01*
X114933Y-75367D01*
X114433Y-74833D01*
X113733Y-74567D01*
X113033Y-74700D01*
X112433Y-75100D01*
X112033Y-76033D01*
X111833Y-76834D01*
Y-77633D01*
X112033Y-78433D01*
X112533Y-79233D01*
X113133Y-79767D01*
X113833Y-79900D01*
X114533Y-79633D01*
X115233Y-78834D01*
G01X120133Y-79900D02*
Y-74567D01*
G01Y-75633D02*
X120633Y-75100D01*
X121133Y-74700D01*
X121833Y-74567D01*
X122333Y-74700D01*
X122933Y-75100D01*
G01X28327Y-27883D02*
X28333Y-67200D01*
G01X4306Y-3903D02*
X28327Y-27883D01*
G01X33751Y-57158D02*
G03X60439Y-30471I-7499J34187D01*
G01X33752Y-52018D02*
X33751Y-57158D01*
G01X33752Y-52018D02*
G03X55299Y-30472I-7500J29047D01*
G01X18752Y-57158D02*
X18751Y-52018D01*
G01X-7935Y-30471D02*
G03X18752Y-57158I34187J7500D01*
G01X-2795Y-30472D02*
X-7935Y-30471D01*
G01X-2795Y-30472D02*
G03X18751Y-52018I29047J7501D01*
G01X4306Y-3903D02*
X4316Y-15903D01*
G01X4306Y-3903D02*
X16306Y-3893D01*
G01X33751Y11216D02*
X33752Y6076D01*
G01X60439Y-15472D02*
G03X33751Y11216I-34187J-7499D01*
G01X55299Y-15471D02*
G03X33752Y6076I-29047J-7500D01*
G01X-7935Y-15472D02*
X-2795Y-15471D01*
G01X18752Y11216D02*
G03X-7935Y-15472I7500J-34187D01*
G01X18751Y6076D02*
X18752Y11216D01*
G01X18751Y6076D02*
G03X-2795Y-15471I7501J-29047D01*
G01X52833Y-602100D02*
X48833D01*
Y-594100D01*
X52833D01*
G01X51233Y-597967D02*
X48833D01*
G01X57533Y-600633D02*
X60133D01*
G01Y-598233D02*
X57533D01*
G01X64633Y-600900D02*
X65233Y-601567D01*
X65933Y-601967D01*
X66833Y-602100D01*
X67733Y-601833D01*
X68433Y-601300D01*
X68933Y-600367D01*
X69033Y-599300D01*
X68833Y-598233D01*
X68333Y-597567D01*
X67633Y-597033D01*
X66933Y-596900D01*
X66233Y-597033D01*
X65333Y-597567D01*
X65633Y-594100D01*
X68333D01*
G01X80233Y-602100D02*
Y-594100D01*
X82833Y-600767D01*
X85433Y-594100D01*
Y-602100D01*
G01X89633Y-594100D02*
X92033D01*
G01X90833D02*
Y-602100D01*
G01X89633D02*
X92033D01*
G01X96833Y-594100D02*
Y-602100D01*
X100833D01*
G01X104733Y-601034D02*
X105533Y-601700D01*
X106433Y-602100D01*
X107233D01*
X108033Y-601700D01*
X108633Y-601034D01*
X108933Y-600100D01*
X108733Y-599167D01*
X108233Y-598367D01*
X107333Y-597833D01*
X106133Y-597567D01*
X105433Y-597033D01*
X105133Y-596100D01*
X105333Y-595167D01*
X105833Y-594500D01*
X106533Y-594100D01*
X107233D01*
X107933Y-594367D01*
X108533Y-595033D01*
G01X122333Y-604767D02*
X121333Y-603433D01*
X120833Y-602100D01*
Y-596767D01*
X121333Y-595433D01*
X122333Y-594100D01*
G01X132633Y-602100D02*
Y-596767D01*
G01Y-597700D02*
X132233Y-597167D01*
X131633Y-596900D01*
X130933Y-596767D01*
X130233Y-597033D01*
X129633Y-597567D01*
X129233Y-598367D01*
X129033Y-599433D01*
X129233Y-600500D01*
X129633Y-601300D01*
X130233Y-601833D01*
X130933Y-602100D01*
X131633Y-601967D01*
X132233Y-601567D01*
X132633Y-601034D01*
G01X138833Y-602100D02*
Y-594100D01*
G01X144333Y-596767D02*
X145533Y-602100D01*
X146833Y-596767D01*
X148133Y-602100D01*
X149333Y-596767D01*
G01X156633Y-602100D02*
Y-596767D01*
G01Y-597700D02*
X156233Y-597167D01*
X155633Y-596900D01*
X154933Y-596767D01*
X154233Y-597033D01*
X153633Y-597567D01*
X153233Y-598367D01*
X153033Y-599433D01*
X153233Y-600500D01*
X153633Y-601300D01*
X154233Y-601833D01*
X154933Y-602100D01*
X155633Y-601967D01*
X156233Y-601567D01*
X156633Y-601034D01*
G01X160733Y-604500D02*
X161333Y-604767D01*
X162133Y-604500D01*
X162633Y-603967D01*
X163033Y-603300D01*
X163633Y-601167D01*
X164933Y-596767D01*
G01X161733D02*
X163633Y-601167D01*
G01X169333D02*
X169833Y-601700D01*
X170533Y-602100D01*
X171133D01*
X171733Y-601833D01*
X172133Y-601433D01*
X172333Y-600900D01*
X172233Y-600100D01*
X171833Y-599700D01*
X170033Y-598900D01*
X169633Y-597967D01*
X169833Y-597300D01*
X170233Y-596900D01*
X170833Y-596767D01*
X171433Y-596900D01*
X172033Y-597300D01*
G01X185133Y-602100D02*
Y-594100D01*
G01X188333Y-596767D02*
X185133Y-599833D01*
G01X186433Y-598633D02*
X188533Y-602100D01*
G01X193333Y-598500D02*
X196533D01*
X196233Y-597567D01*
X195733Y-597033D01*
X195033Y-596767D01*
X194333Y-596900D01*
X193733Y-597300D01*
X193333Y-598233D01*
X193133Y-599034D01*
Y-599833D01*
X193333Y-600633D01*
X193833Y-601433D01*
X194433Y-601967D01*
X195133Y-602100D01*
X195833Y-601833D01*
X196533Y-601034D01*
G01X201333Y-598500D02*
X204533D01*
X204233Y-597567D01*
X203733Y-597033D01*
X203033Y-596767D01*
X202333Y-596900D01*
X201733Y-597300D01*
X201333Y-598233D01*
X201133Y-599034D01*
Y-599833D01*
X201333Y-600633D01*
X201833Y-601433D01*
X202433Y-601967D01*
X203133Y-602100D01*
X203833Y-601833D01*
X204533Y-601034D01*
G01X209033Y-604767D02*
Y-596767D01*
G01Y-597967D02*
X209533Y-597300D01*
X210033Y-596900D01*
X210833Y-596767D01*
X211533Y-596900D01*
X212233Y-597567D01*
X212533Y-598500D01*
X212633Y-599433D01*
X212533Y-600367D01*
X212233Y-601300D01*
X211633Y-601833D01*
X210833Y-602100D01*
X210133Y-601967D01*
X209433Y-601567D01*
X209033Y-601034D01*
G01X224633Y-600900D02*
X225233Y-601567D01*
X225933Y-601967D01*
X226833Y-602100D01*
X227733Y-601833D01*
X228433Y-601300D01*
X228933Y-600367D01*
X229033Y-599300D01*
X228833Y-598233D01*
X228333Y-597567D01*
X227633Y-597033D01*
X226933Y-596900D01*
X226233Y-597033D01*
X225333Y-597567D01*
X225633Y-594100D01*
X228333D01*
G01X239833Y-602100D02*
Y-596767D01*
G01Y-598233D02*
X240133Y-597567D01*
X240633Y-597033D01*
X241333Y-596767D01*
X242033Y-597033D01*
X242533Y-597567D01*
X242833Y-598233D01*
Y-602100D01*
G01Y-598233D02*
X243133Y-597567D01*
X243633Y-597033D01*
X244333Y-596767D01*
X245033Y-597033D01*
X245533Y-597567D01*
X245833Y-598367D01*
Y-602100D01*
G01X250833Y-596767D02*
Y-602100D01*
G01Y-594633D02*
X250633Y-594500D01*
Y-594233D01*
X250833Y-594100D01*
X251033Y-594233D01*
Y-594500D01*
X250833Y-594633D01*
G01X258833Y-602100D02*
Y-594100D01*
G01X265333Y-601167D02*
X265833Y-601700D01*
X266533Y-602100D01*
X267133D01*
X267733Y-601833D01*
X268133Y-601433D01*
X268333Y-600900D01*
X268233Y-600100D01*
X267833Y-599700D01*
X266033Y-598900D01*
X265633Y-597967D01*
X265833Y-597300D01*
X266233Y-596900D01*
X266833Y-596767D01*
X267433Y-596900D01*
X268033Y-597300D01*
G01X275333Y-604767D02*
X276333Y-603433D01*
X276833Y-602100D01*
Y-596767D01*
X276333Y-595433D01*
X275333Y-594100D01*
G01X85433Y-531567D02*
X84833Y-531167D01*
X84133Y-530900D01*
X83333D01*
X82433Y-531300D01*
X81733Y-531967D01*
X81233Y-532767D01*
X80833Y-534100D01*
X80733Y-535300D01*
X80933Y-536500D01*
X81233Y-537300D01*
X81833Y-538100D01*
X82533Y-538633D01*
X83233Y-538900D01*
X83933D01*
X84633Y-538633D01*
X85233Y-538233D01*
X85733Y-537700D01*
G01X52133Y-507500D02*
X54633Y-510000D01*
G01X52033Y-513600D02*
X51933Y-513700D01*
G01X52033Y-464600D02*
Y-513600D01*
G01X98033Y-533900D02*
X101233Y-537100D01*
G01X98033Y-533800D02*
Y-533900D01*
G01X97933Y-533700D02*
X100933Y-530700D01*
G01X98133Y-533900D02*
X97933Y-533700D01*
G01X129233Y-533900D02*
X98133D01*
G01X72633Y-534200D02*
X70033Y-536800D01*
G01X72833Y-534200D02*
X72633D01*
G01X72933Y-533900D02*
X70333Y-531300D01*
G01X72633Y-534200D02*
X72933Y-533900D01*
G01X97933Y-501300D02*
Y-549300D01*
G01X72933Y-501800D02*
Y-549400D01*
G01X52133Y-507300D02*
Y-507500D01*
G01Y-507300D02*
X54733Y-504700D01*
G01X52233Y-507400D02*
X52133Y-507300D01*
G01X67433Y-507400D02*
X52233D01*
G01X97933Y-501800D02*
X192333D01*
G01X73622Y-495844D02*
Y-502090D01*
G01X51968Y-464533D02*
G03X73622Y-495844I33464J0D01*
G01X51968Y-448785D02*
Y-464533D01*
G01X97244Y-502090D02*
G03X124803Y-464533I-11812J37557D01*
G01X97244Y-495844D02*
G03X118898Y-464533I-11810J31311D01*
G01X97244Y-502090D02*
Y-495844D01*
G01X51968Y-393667D02*
Y-409415D01*
G01X73622Y-362356D02*
G03X51968Y-393667I11810J-31311D01*
G01X80433Y-341300D02*
X82933Y-333300D01*
X85433Y-341300D01*
G01X84533Y-338500D02*
X81333D01*
G01X96933Y-355600D02*
X186233D01*
G01X104133Y-335100D02*
X125033D01*
G01X73622Y-356110D02*
Y-362356D01*
G01X124803Y-393667D02*
G03X97244Y-356110I-39371J0D01*
G01Y-362356D02*
Y-356110D01*
G01X118898Y-393667D02*
G03X97244Y-362356I-33464J0D01*
G01X109923Y-23420D02*
X111923D01*
Y-25820D01*
X111323Y-26620D01*
X110623Y-27153D01*
X109623Y-27420D01*
X108623Y-27153D01*
X107923Y-26620D01*
X107323Y-25820D01*
X106923Y-24887D01*
X106723Y-23820D01*
Y-22887D01*
X106923Y-22087D01*
X107323Y-21153D01*
X107923Y-20353D01*
X108523Y-19820D01*
X109323Y-19420D01*
X110023D01*
X110823Y-19687D01*
X111423Y-20220D01*
G01X119123Y-27420D02*
Y-22087D01*
G01Y-23020D02*
X118723Y-22487D01*
X118123Y-22220D01*
X117423Y-22087D01*
X116723Y-22353D01*
X116123Y-22887D01*
X115723Y-23687D01*
X115523Y-24753D01*
X115723Y-25820D01*
X116123Y-26620D01*
X116723Y-27153D01*
X117423Y-27420D01*
X118123Y-27287D01*
X118723Y-26887D01*
X119123Y-26354D01*
G01X123523Y-30087D02*
Y-22087D01*
G01Y-23287D02*
X124023Y-22620D01*
X124523Y-22220D01*
X125323Y-22087D01*
X126023Y-22220D01*
X126723Y-22887D01*
X127023Y-23820D01*
X127123Y-24753D01*
X127023Y-25687D01*
X126723Y-26620D01*
X126123Y-27153D01*
X125323Y-27420D01*
X124623Y-27287D01*
X123923Y-26887D01*
X123523Y-26354D01*
G01X138323Y-19420D02*
X139723Y-27420D01*
X141323Y-19420D01*
X142923Y-27420D01*
X144323Y-19420D01*
G01X149323Y-22087D02*
Y-27420D01*
G01Y-19953D02*
X149123Y-19820D01*
Y-19553D01*
X149323Y-19420D01*
X149523Y-19553D01*
Y-19820D01*
X149323Y-19953D01*
G01X159123Y-19420D02*
Y-27420D01*
G01Y-26220D02*
X158723Y-26887D01*
X158123Y-27287D01*
X157423Y-27420D01*
X156623Y-27153D01*
X156023Y-26487D01*
X155623Y-25687D01*
X155523Y-24753D01*
X155623Y-23820D01*
X156023Y-23020D01*
X156623Y-22353D01*
X157423Y-22087D01*
X158123Y-22220D01*
X158623Y-22487D01*
X159123Y-23020D01*
G01X165323Y-19420D02*
Y-27420D01*
G01X163923Y-22087D02*
X166723D01*
G01X171623Y-27420D02*
Y-19420D01*
G01Y-23287D02*
X172123Y-22620D01*
X172623Y-22220D01*
X173423Y-22087D01*
X174023Y-22220D01*
X174723Y-22753D01*
X175023Y-23553D01*
Y-27420D01*
G01X61753Y-22730D02*
X103753D01*
G01X61753D02*
X69753Y-30730D01*
G01X61753Y-22730D02*
X69753Y-14730D01*
G01X60439Y-30471D02*
X55299Y-30472D01*
G01X74213Y27840D02*
X106213D01*
G01X50213Y3840D02*
X74213Y27840D01*
G01X50213Y3840D02*
Y15840D01*
G01Y3840D02*
X62213D01*
G01X55299Y-15471D02*
X60439Y-15472D01*
G01X151133Y-501300D02*
X154733Y-497700D01*
G01X150933Y-501300D02*
X151133D01*
G01X150333Y-501400D02*
X146433Y-497500D01*
G01X150833Y-501400D02*
X150333D01*
G01X150733Y-501200D02*
X150133Y-501800D01*
G01X150733Y-447500D02*
Y-501200D01*
G01X124803Y-448785D02*
Y-464533D01*
G01X118898Y-448785D02*
X124803D01*
G01X118898Y-464533D02*
Y-448785D01*
G01X151333Y-428633D02*
X151733Y-428233D01*
X152033Y-427567D01*
X152233Y-426633D01*
X152033Y-425833D01*
X151633Y-425300D01*
X150933Y-424900D01*
X148233D01*
Y-432900D01*
X151533D01*
X152233Y-432367D01*
X152633Y-431567D01*
X152833Y-430633D01*
X152633Y-429700D01*
X152033Y-428900D01*
X151333Y-428633D01*
X148233D01*
G01X149633Y-407400D02*
X150133Y-407900D01*
G01X149633Y-356200D02*
Y-407400D01*
G01X125133Y-393200D02*
Y-320700D01*
G01X124803Y-409415D02*
X118898D01*
G01X124803Y-393667D02*
Y-409415D01*
G01X118898D02*
Y-393667D01*
G01X149633Y-355800D02*
X152833Y-359000D01*
G01X149533Y-355700D02*
X146133Y-359100D01*
G01X125133Y-335100D02*
X122533Y-337700D01*
G01X125133Y-335000D02*
Y-335100D01*
G01X122433Y-332100D02*
X122333D01*
G01X125233Y-334900D02*
X122433Y-332100D01*
G01X125033Y-335100D02*
X125233Y-334900D01*
G01X125133Y-320700D02*
X125233Y-320600D01*
G01X112763Y21180D02*
X111963Y21313D01*
X111263Y21847D01*
X110663Y22647D01*
X110263Y23580D01*
X110063Y24647D01*
Y25713D01*
X110263Y26780D01*
X110663Y27713D01*
X111263Y28513D01*
X111963Y29047D01*
X112763Y29180D01*
X113563Y29047D01*
X114263Y28513D01*
X114863Y27713D01*
X115263Y26780D01*
X115463Y25713D01*
Y24647D01*
X115263Y23580D01*
X114863Y22647D01*
X114263Y21847D01*
X113563Y21313D01*
X112763Y21180D01*
G01X119063Y26513D02*
Y22780D01*
X119463Y21847D01*
X120063Y21313D01*
X120763Y21180D01*
X121463Y21313D01*
X122063Y21847D01*
X122463Y22780D01*
G01Y21180D02*
Y26513D01*
G01X128763Y29180D02*
Y21180D01*
G01X127363Y26513D02*
X130163D01*
G01X135263Y24780D02*
X138463D01*
X138163Y25713D01*
X137663Y26247D01*
X136963Y26513D01*
X136263Y26380D01*
X135663Y25980D01*
X135263Y25047D01*
X135063Y24246D01*
Y23447D01*
X135263Y22647D01*
X135763Y21847D01*
X136363Y21313D01*
X137063Y21180D01*
X137763Y21447D01*
X138463Y22246D01*
G01X143363Y21180D02*
Y26513D01*
G01Y25447D02*
X143863Y25980D01*
X144363Y26380D01*
X145063Y26513D01*
X145563Y26380D01*
X146163Y25980D01*
G01X158563Y21180D02*
Y29180D01*
X160563D01*
X161363Y28780D01*
X161963Y28247D01*
X162463Y27447D01*
X162863Y26513D01*
X162963Y25180D01*
X162863Y23847D01*
X162463Y22913D01*
X161963Y22113D01*
X161363Y21580D01*
X160563Y21180D01*
X158563D01*
G01X168763Y26513D02*
Y21180D01*
G01Y28647D02*
X168563Y28780D01*
Y29047D01*
X168763Y29180D01*
X168963Y29047D01*
Y28780D01*
X168763Y28647D01*
G01X178563Y21180D02*
Y26513D01*
G01Y25580D02*
X178163Y26113D01*
X177563Y26380D01*
X176863Y26513D01*
X176163Y26247D01*
X175563Y25713D01*
X175163Y24913D01*
X174963Y23847D01*
X175163Y22780D01*
X175563Y21980D01*
X176163Y21447D01*
X176863Y21180D01*
X177563Y21313D01*
X178163Y21713D01*
X178563Y22246D01*
G01X181763Y21180D02*
Y26513D01*
G01Y25047D02*
X182063Y25713D01*
X182563Y26247D01*
X183263Y26513D01*
X183963Y26247D01*
X184463Y25713D01*
X184763Y25047D01*
Y21180D01*
G01Y25047D02*
X185063Y25713D01*
X185563Y26247D01*
X186263Y26513D01*
X186963Y26247D01*
X187463Y25713D01*
X187763Y24913D01*
Y21180D01*
G01X191263Y24780D02*
X194463D01*
X194163Y25713D01*
X193663Y26247D01*
X192963Y26513D01*
X192263Y26380D01*
X191663Y25980D01*
X191263Y25047D01*
X191063Y24246D01*
Y23447D01*
X191263Y22647D01*
X191763Y21847D01*
X192363Y21313D01*
X193063Y21180D01*
X193763Y21447D01*
X194463Y22246D01*
G01X200763Y29180D02*
Y21180D01*
G01X199363Y26513D02*
X202163D01*
G01X207263Y24780D02*
X210463D01*
X210163Y25713D01*
X209663Y26247D01*
X208963Y26513D01*
X208263Y26380D01*
X207663Y25980D01*
X207263Y25047D01*
X207063Y24246D01*
Y23447D01*
X207263Y22647D01*
X207763Y21847D01*
X208363Y21313D01*
X209063Y21180D01*
X209763Y21447D01*
X210463Y22246D01*
G01X215363Y21180D02*
Y26513D01*
G01Y25447D02*
X215863Y25980D01*
X216363Y26380D01*
X217063Y26513D01*
X217563Y26380D01*
X218163Y25980D01*
G01X192333Y-501800D02*
X192933Y-502400D01*
G01X186233Y-355600D02*
X186733Y-355100D01*
G01X179533Y-151100D02*
Y-143100D01*
X184133Y-151100D01*
Y-143100D01*
G01X188133Y-145767D02*
Y-149500D01*
X188533Y-150433D01*
X189133Y-150967D01*
X189833Y-151100D01*
X190533Y-150967D01*
X191133Y-150433D01*
X191533Y-149500D01*
G01Y-151100D02*
Y-145767D01*
G01X194833Y-151100D02*
Y-145767D01*
G01Y-147233D02*
X195133Y-146567D01*
X195633Y-146033D01*
X196333Y-145767D01*
X197033Y-146033D01*
X197533Y-146567D01*
X197833Y-147233D01*
Y-151100D01*
G01Y-147233D02*
X198133Y-146567D01*
X198633Y-146033D01*
X199333Y-145767D01*
X200033Y-146033D01*
X200533Y-146567D01*
X200833Y-147367D01*
Y-151100D01*
G01X211733Y-150034D02*
X212533Y-150700D01*
X213433Y-151100D01*
X214233D01*
X215033Y-150700D01*
X215633Y-150034D01*
X215933Y-149100D01*
X215733Y-148167D01*
X215233Y-147367D01*
X214333Y-146833D01*
X213133Y-146567D01*
X212433Y-146033D01*
X212133Y-145100D01*
X212333Y-144167D01*
X212833Y-143500D01*
X213533Y-143100D01*
X214233D01*
X214933Y-143367D01*
X215533Y-144033D01*
G01X220033Y-153767D02*
Y-145767D01*
G01Y-146967D02*
X220533Y-146300D01*
X221033Y-145900D01*
X221833Y-145767D01*
X222533Y-145900D01*
X223233Y-146567D01*
X223533Y-147500D01*
X223633Y-148433D01*
X223533Y-149367D01*
X223233Y-150300D01*
X222633Y-150833D01*
X221833Y-151100D01*
X221133Y-150967D01*
X220433Y-150567D01*
X220033Y-150034D01*
G01X229833Y-151100D02*
X229233Y-150967D01*
X228633Y-150433D01*
X228233Y-149500D01*
X228033Y-148433D01*
X228233Y-147367D01*
X228633Y-146433D01*
X229233Y-145900D01*
X229833Y-145767D01*
X230433Y-145900D01*
X231033Y-146433D01*
X231433Y-147367D01*
X231533Y-148433D01*
X231433Y-149500D01*
X231033Y-150433D01*
X230433Y-150967D01*
X229833Y-151100D01*
G01X236133D02*
Y-143100D01*
G01X239333Y-145767D02*
X236133Y-148833D01*
G01X237433Y-147633D02*
X239533Y-151100D01*
G01X244333Y-147500D02*
X247533D01*
X247233Y-146567D01*
X246733Y-146033D01*
X246033Y-145767D01*
X245333Y-145900D01*
X244733Y-146300D01*
X244333Y-147233D01*
X244133Y-148034D01*
Y-148833D01*
X244333Y-149633D01*
X244833Y-150433D01*
X245433Y-150967D01*
X246133Y-151100D01*
X246833Y-150833D01*
X247533Y-150034D01*
G01X252333Y-150167D02*
X252833Y-150700D01*
X253533Y-151100D01*
X254133D01*
X254733Y-150833D01*
X255133Y-150433D01*
X255333Y-149900D01*
X255233Y-149100D01*
X254833Y-148700D01*
X253033Y-147900D01*
X252633Y-146967D01*
X252833Y-146300D01*
X253233Y-145900D01*
X253833Y-145767D01*
X254433Y-145900D01*
X255033Y-146300D01*
G01X260533Y-149633D02*
X263133D01*
G01Y-147233D02*
X260533D01*
G01X271033Y-151100D02*
Y-143100D01*
X267333Y-148833D01*
X272333D01*
G01X180433Y-163100D02*
X182433D01*
Y-165500D01*
X181833Y-166300D01*
X181133Y-166833D01*
X180133Y-167100D01*
X179133Y-166833D01*
X178433Y-166300D01*
X177833Y-165500D01*
X177433Y-164567D01*
X177233Y-163500D01*
Y-162567D01*
X177433Y-161767D01*
X177833Y-160833D01*
X178433Y-160033D01*
X179033Y-159500D01*
X179833Y-159100D01*
X180533D01*
X181333Y-159367D01*
X181933Y-159900D01*
G01X189633Y-167100D02*
Y-161767D01*
G01Y-162700D02*
X189233Y-162167D01*
X188633Y-161900D01*
X187933Y-161767D01*
X187233Y-162033D01*
X186633Y-162567D01*
X186233Y-163367D01*
X186033Y-164433D01*
X186233Y-165500D01*
X186633Y-166300D01*
X187233Y-166833D01*
X187933Y-167100D01*
X188633Y-166967D01*
X189233Y-166567D01*
X189633Y-166034D01*
G01X194033Y-169767D02*
Y-161767D01*
G01Y-162967D02*
X194533Y-162300D01*
X195033Y-161900D01*
X195833Y-161767D01*
X196533Y-161900D01*
X197233Y-162567D01*
X197533Y-163500D01*
X197633Y-164433D01*
X197533Y-165367D01*
X197233Y-166300D01*
X196633Y-166833D01*
X195833Y-167100D01*
X195133Y-166967D01*
X194433Y-166567D01*
X194033Y-166034D01*
G01X208833Y-159100D02*
X210233Y-167100D01*
X211833Y-159100D01*
X213433Y-167100D01*
X214833Y-159100D01*
G01X219833Y-161767D02*
Y-167100D01*
G01Y-159633D02*
X219633Y-159500D01*
Y-159233D01*
X219833Y-159100D01*
X220033Y-159233D01*
Y-159500D01*
X219833Y-159633D01*
G01X229633Y-159100D02*
Y-167100D01*
G01Y-165900D02*
X229233Y-166567D01*
X228633Y-166967D01*
X227933Y-167100D01*
X227133Y-166833D01*
X226533Y-166167D01*
X226133Y-165367D01*
X226033Y-164433D01*
X226133Y-163500D01*
X226533Y-162700D01*
X227133Y-162033D01*
X227933Y-161767D01*
X228633Y-161900D01*
X229133Y-162167D01*
X229633Y-162700D01*
G01X235833Y-159100D02*
Y-167100D01*
G01X234433Y-161767D02*
X237233D01*
G01X242133Y-167100D02*
Y-159100D01*
G01Y-162967D02*
X242633Y-162300D01*
X243133Y-161900D01*
X243933Y-161767D01*
X244533Y-161900D01*
X245233Y-162433D01*
X245533Y-163233D01*
Y-167100D01*
G01X250533Y-165633D02*
X253133D01*
G01Y-163233D02*
X250533D01*
G01X257633Y-165500D02*
X258233Y-166433D01*
X259033Y-166967D01*
X259933Y-167100D01*
X260733Y-166967D01*
X261533Y-166300D01*
X262033Y-165500D01*
X262133Y-164700D01*
X261933Y-163767D01*
X261233Y-163100D01*
X260533Y-162833D01*
X259633D01*
G01X260533D02*
X261133Y-162433D01*
X261633Y-161767D01*
X261833Y-160967D01*
X261633Y-160167D01*
X261133Y-159500D01*
X260233Y-159100D01*
X259333Y-159233D01*
X258433Y-159767D01*
G01X267833Y-159100D02*
X267033Y-159367D01*
X266433Y-160033D01*
X266033Y-160833D01*
X265733Y-161900D01*
X265633Y-163100D01*
X265733Y-164300D01*
X266033Y-165367D01*
X266433Y-166167D01*
X267033Y-166833D01*
X267833Y-167100D01*
X268633Y-166833D01*
X269233Y-166167D01*
X269633Y-165367D01*
X269933Y-164300D01*
X270033Y-163100D01*
X269933Y-161900D01*
X269633Y-160833D01*
X269233Y-160033D01*
X268633Y-159367D01*
X267833Y-159100D01*
G01X176633Y-101100D02*
X179033D01*
G01X177833D02*
Y-109100D01*
G01X176633D02*
X179033D01*
G01X184133D02*
Y-103767D01*
G01Y-105100D02*
X184533Y-104433D01*
X185133Y-103900D01*
X185933Y-103767D01*
X186633Y-103900D01*
X187233Y-104433D01*
X187533Y-105367D01*
Y-109100D01*
G01X192133D02*
Y-103767D01*
G01Y-105100D02*
X192533Y-104433D01*
X193133Y-103900D01*
X193933Y-103767D01*
X194633Y-103900D01*
X195233Y-104433D01*
X195533Y-105367D01*
Y-109100D01*
G01X200333Y-105500D02*
X203533D01*
X203233Y-104567D01*
X202733Y-104033D01*
X202033Y-103767D01*
X201333Y-103900D01*
X200733Y-104300D01*
X200333Y-105233D01*
X200133Y-106034D01*
Y-106833D01*
X200333Y-107633D01*
X200833Y-108433D01*
X201433Y-108967D01*
X202133Y-109100D01*
X202833Y-108833D01*
X203533Y-108034D01*
G01X208433Y-109100D02*
Y-103767D01*
G01Y-104833D02*
X208933Y-104300D01*
X209433Y-103900D01*
X210133Y-103767D01*
X210633Y-103900D01*
X211233Y-104300D01*
G01X223633Y-109100D02*
Y-101100D01*
X225633D01*
X226433Y-101500D01*
X227033Y-102033D01*
X227533Y-102833D01*
X227933Y-103767D01*
X228033Y-105100D01*
X227933Y-106433D01*
X227533Y-107367D01*
X227033Y-108167D01*
X226433Y-108700D01*
X225633Y-109100D01*
X223633D01*
G01X233833Y-103767D02*
Y-109100D01*
G01Y-101633D02*
X233633Y-101500D01*
Y-101233D01*
X233833Y-101100D01*
X234033Y-101233D01*
Y-101500D01*
X233833Y-101633D01*
G01X243633Y-109100D02*
Y-103767D01*
G01Y-104700D02*
X243233Y-104167D01*
X242633Y-103900D01*
X241933Y-103767D01*
X241233Y-104033D01*
X240633Y-104567D01*
X240233Y-105367D01*
X240033Y-106433D01*
X240233Y-107500D01*
X240633Y-108300D01*
X241233Y-108833D01*
X241933Y-109100D01*
X242633Y-108967D01*
X243233Y-108567D01*
X243633Y-108034D01*
G01X246833Y-109100D02*
Y-103767D01*
G01Y-105233D02*
X247133Y-104567D01*
X247633Y-104033D01*
X248333Y-103767D01*
X249033Y-104033D01*
X249533Y-104567D01*
X249833Y-105233D01*
Y-109100D01*
G01Y-105233D02*
X250133Y-104567D01*
X250633Y-104033D01*
X251333Y-103767D01*
X252033Y-104033D01*
X252533Y-104567D01*
X252833Y-105367D01*
Y-109100D01*
G01X256333Y-105500D02*
X259533D01*
X259233Y-104567D01*
X258733Y-104033D01*
X258033Y-103767D01*
X257333Y-103900D01*
X256733Y-104300D01*
X256333Y-105233D01*
X256133Y-106034D01*
Y-106833D01*
X256333Y-107633D01*
X256833Y-108433D01*
X257433Y-108967D01*
X258133Y-109100D01*
X258833Y-108833D01*
X259533Y-108034D01*
G01X265833Y-101100D02*
Y-109100D01*
G01X264433Y-103767D02*
X267233D01*
G01X272333Y-105500D02*
X275533D01*
X275233Y-104567D01*
X274733Y-104033D01*
X274033Y-103767D01*
X273333Y-103900D01*
X272733Y-104300D01*
X272333Y-105233D01*
X272133Y-106034D01*
Y-106833D01*
X272333Y-107633D01*
X272833Y-108433D01*
X273433Y-108967D01*
X274133Y-109100D01*
X274833Y-108833D01*
X275533Y-108034D01*
G01X280433Y-109100D02*
Y-103767D01*
G01Y-104833D02*
X280933Y-104300D01*
X281433Y-103900D01*
X282133Y-103767D01*
X282633Y-103900D01*
X283233Y-104300D01*
G01X288533Y-107633D02*
X291133D01*
G01Y-105233D02*
X288533D01*
G01X296133Y-108167D02*
X296833Y-108833D01*
X297633Y-109100D01*
X298433Y-108833D01*
X299133Y-108034D01*
X299633Y-106833D01*
X299833Y-105633D01*
Y-104167D01*
X299633Y-102967D01*
X299133Y-101900D01*
X298533Y-101367D01*
X297833Y-101100D01*
X297033Y-101367D01*
X296433Y-101900D01*
X296033Y-102700D01*
X295833Y-103767D01*
X296033Y-104700D01*
X296533Y-105633D01*
X297133Y-106167D01*
X297833Y-106300D01*
X298633Y-106034D01*
X299233Y-105367D01*
X299833Y-104167D01*
G01X303633Y-107500D02*
X304233Y-108433D01*
X305033Y-108967D01*
X305933Y-109100D01*
X306733Y-108967D01*
X307533Y-108300D01*
X308033Y-107500D01*
X308133Y-106700D01*
X307933Y-105767D01*
X307233Y-105100D01*
X306533Y-104833D01*
X305633D01*
G01X306533D02*
X307133Y-104433D01*
X307633Y-103767D01*
X307833Y-102967D01*
X307633Y-102167D01*
X307133Y-101500D01*
X306233Y-101100D01*
X305333Y-101233D01*
X304433Y-101767D01*
G01X179833Y-131100D02*
X179033Y-130967D01*
X178333Y-130433D01*
X177733Y-129633D01*
X177333Y-128700D01*
X177133Y-127633D01*
Y-126567D01*
X177333Y-125500D01*
X177733Y-124567D01*
X178333Y-123767D01*
X179033Y-123233D01*
X179833Y-123100D01*
X180633Y-123233D01*
X181333Y-123767D01*
X181933Y-124567D01*
X182333Y-125500D01*
X182533Y-126567D01*
Y-127633D01*
X182333Y-128700D01*
X181933Y-129633D01*
X181333Y-130433D01*
X180633Y-130967D01*
X179833Y-131100D01*
G01X186133Y-125767D02*
Y-129500D01*
X186533Y-130433D01*
X187133Y-130967D01*
X187833Y-131100D01*
X188533Y-130967D01*
X189133Y-130433D01*
X189533Y-129500D01*
G01Y-131100D02*
Y-125767D01*
G01X195833Y-123100D02*
Y-131100D01*
G01X194433Y-125767D02*
X197233D01*
G01X202333Y-127500D02*
X205533D01*
X205233Y-126567D01*
X204733Y-126033D01*
X204033Y-125767D01*
X203333Y-125900D01*
X202733Y-126300D01*
X202333Y-127233D01*
X202133Y-128034D01*
Y-128833D01*
X202333Y-129633D01*
X202833Y-130433D01*
X203433Y-130967D01*
X204133Y-131100D01*
X204833Y-130833D01*
X205533Y-130034D01*
G01X210433Y-131100D02*
Y-125767D01*
G01Y-126833D02*
X210933Y-126300D01*
X211433Y-125900D01*
X212133Y-125767D01*
X212633Y-125900D01*
X213233Y-126300D01*
G01X225633Y-131100D02*
Y-123100D01*
X227633D01*
X228433Y-123500D01*
X229033Y-124033D01*
X229533Y-124833D01*
X229933Y-125767D01*
X230033Y-127100D01*
X229933Y-128433D01*
X229533Y-129367D01*
X229033Y-130167D01*
X228433Y-130700D01*
X227633Y-131100D01*
X225633D01*
G01X235833Y-125767D02*
Y-131100D01*
G01Y-123633D02*
X235633Y-123500D01*
Y-123233D01*
X235833Y-123100D01*
X236033Y-123233D01*
Y-123500D01*
X235833Y-123633D01*
G01X245633Y-131100D02*
Y-125767D01*
G01Y-126700D02*
X245233Y-126167D01*
X244633Y-125900D01*
X243933Y-125767D01*
X243233Y-126033D01*
X242633Y-126567D01*
X242233Y-127367D01*
X242033Y-128433D01*
X242233Y-129500D01*
X242633Y-130300D01*
X243233Y-130833D01*
X243933Y-131100D01*
X244633Y-130967D01*
X245233Y-130567D01*
X245633Y-130034D01*
G01X248833Y-131100D02*
Y-125767D01*
G01Y-127233D02*
X249133Y-126567D01*
X249633Y-126033D01*
X250333Y-125767D01*
X251033Y-126033D01*
X251533Y-126567D01*
X251833Y-127233D01*
Y-131100D01*
G01Y-127233D02*
X252133Y-126567D01*
X252633Y-126033D01*
X253333Y-125767D01*
X254033Y-126033D01*
X254533Y-126567D01*
X254833Y-127367D01*
Y-131100D01*
G01X258333Y-127500D02*
X261533D01*
X261233Y-126567D01*
X260733Y-126033D01*
X260033Y-125767D01*
X259333Y-125900D01*
X258733Y-126300D01*
X258333Y-127233D01*
X258133Y-128034D01*
Y-128833D01*
X258333Y-129633D01*
X258833Y-130433D01*
X259433Y-130967D01*
X260133Y-131100D01*
X260833Y-130833D01*
X261533Y-130034D01*
G01X267833Y-123100D02*
Y-131100D01*
G01X266433Y-125767D02*
X269233D01*
G01X274333Y-127500D02*
X277533D01*
X277233Y-126567D01*
X276733Y-126033D01*
X276033Y-125767D01*
X275333Y-125900D01*
X274733Y-126300D01*
X274333Y-127233D01*
X274133Y-128034D01*
Y-128833D01*
X274333Y-129633D01*
X274833Y-130433D01*
X275433Y-130967D01*
X276133Y-131100D01*
X276833Y-130833D01*
X277533Y-130034D01*
G01X282433Y-131100D02*
Y-125767D01*
G01Y-126833D02*
X282933Y-126300D01*
X283433Y-125900D01*
X284133Y-125767D01*
X284633Y-125900D01*
X285233Y-126300D01*
G01X290533Y-129633D02*
X293133D01*
G01Y-127233D02*
X290533D01*
G01X299833Y-131100D02*
Y-123100D01*
X298633Y-124700D01*
G01Y-131100D02*
X301033D01*
G01X307833Y-123100D02*
X307033Y-123367D01*
X306433Y-124033D01*
X306033Y-124833D01*
X305733Y-125900D01*
X305633Y-127100D01*
X305733Y-128300D01*
X306033Y-129367D01*
X306433Y-130167D01*
X307033Y-130833D01*
X307833Y-131100D01*
X308633Y-130833D01*
X309233Y-130167D01*
X309633Y-129367D01*
X309933Y-128300D01*
X310033Y-127100D01*
X309933Y-125900D01*
X309633Y-124833D01*
X309233Y-124033D01*
X308633Y-123367D01*
X307833Y-123100D01*
G01X313633Y-129500D02*
X314233Y-130433D01*
X315033Y-130967D01*
X315933Y-131100D01*
X316733Y-130967D01*
X317533Y-130300D01*
X318033Y-129500D01*
X318133Y-128700D01*
X317933Y-127767D01*
X317233Y-127100D01*
X316533Y-126833D01*
X315633D01*
G01X316533D02*
X317133Y-126433D01*
X317633Y-125767D01*
X317833Y-124967D01*
X317633Y-124167D01*
X317133Y-123500D01*
X316233Y-123100D01*
X315333Y-123233D01*
X314433Y-123767D01*
G01X465433Y161800D02*
Y-707100D01*
G01X474233Y-620200D02*
X476633D01*
G01X475433D02*
Y-628200D01*
G01X474233D02*
X476633D01*
G01X482833D02*
Y-621400D01*
X483033Y-620733D01*
X483433Y-620333D01*
X484033Y-620200D01*
X484633Y-620467D01*
X484933Y-621133D01*
G01X483733Y-623400D02*
X481733D01*
G01X499433Y-622867D02*
Y-628200D01*
G01Y-620733D02*
X499233Y-620600D01*
Y-620333D01*
X499433Y-620200D01*
X499633Y-620333D01*
Y-620600D01*
X499433Y-620733D01*
G01X505933Y-627267D02*
X506433Y-627800D01*
X507133Y-628200D01*
X507733D01*
X508333Y-627933D01*
X508733Y-627533D01*
X508933Y-627000D01*
X508833Y-626200D01*
X508433Y-625800D01*
X506633Y-625000D01*
X506233Y-624067D01*
X506433Y-623400D01*
X506833Y-623000D01*
X507433Y-622867D01*
X508033Y-623000D01*
X508633Y-623400D01*
G01X522033Y-630200D02*
X522733Y-630733D01*
X523533Y-630867D01*
X524233Y-630733D01*
X524833Y-630067D01*
X525233Y-629133D01*
Y-622867D01*
G01Y-623933D02*
X524833Y-623400D01*
X524233Y-623000D01*
X523533Y-622867D01*
X522733Y-623133D01*
X522233Y-623667D01*
X521833Y-624600D01*
X521633Y-625533D01*
X521733Y-626333D01*
X522133Y-627267D01*
X522733Y-627933D01*
X523533Y-628200D01*
X524133Y-628067D01*
X524833Y-627533D01*
X525233Y-627000D01*
G01X530033Y-628200D02*
Y-622867D01*
G01Y-623933D02*
X530533Y-623400D01*
X531033Y-623000D01*
X531733Y-622867D01*
X532233Y-623000D01*
X532833Y-623400D01*
G01X537933Y-624600D02*
X541133D01*
X540833Y-623667D01*
X540333Y-623133D01*
X539633Y-622867D01*
X538933Y-623000D01*
X538333Y-623400D01*
X537933Y-624333D01*
X537733Y-625134D01*
Y-625933D01*
X537933Y-626733D01*
X538433Y-627533D01*
X539033Y-628067D01*
X539733Y-628200D01*
X540433Y-627933D01*
X541133Y-627134D01*
G01X549233Y-628200D02*
Y-622867D01*
G01Y-623800D02*
X548833Y-623267D01*
X548233Y-623000D01*
X547533Y-622867D01*
X546833Y-623133D01*
X546233Y-623667D01*
X545833Y-624467D01*
X545633Y-625533D01*
X545833Y-626600D01*
X546233Y-627400D01*
X546833Y-627933D01*
X547533Y-628200D01*
X548233Y-628067D01*
X548833Y-627667D01*
X549233Y-627134D01*
G01X555433Y-620200D02*
Y-628200D01*
G01X554033Y-622867D02*
X556833D01*
G01X561933Y-624600D02*
X565133D01*
X564833Y-623667D01*
X564333Y-623133D01*
X563633Y-622867D01*
X562933Y-623000D01*
X562333Y-623400D01*
X561933Y-624333D01*
X561733Y-625134D01*
Y-625933D01*
X561933Y-626733D01*
X562433Y-627533D01*
X563033Y-628067D01*
X563733Y-628200D01*
X564433Y-627933D01*
X565133Y-627134D01*
G01X570033Y-628200D02*
Y-622867D01*
G01Y-623933D02*
X570533Y-623400D01*
X571033Y-623000D01*
X571733Y-622867D01*
X572233Y-623000D01*
X572833Y-623400D01*
G01X587433Y-620200D02*
Y-628200D01*
G01X586033Y-622867D02*
X588833D01*
G01X593733Y-628200D02*
Y-620200D01*
G01Y-624067D02*
X594233Y-623400D01*
X594733Y-623000D01*
X595533Y-622867D01*
X596133Y-623000D01*
X596833Y-623533D01*
X597133Y-624333D01*
Y-628200D01*
G01X605233D02*
Y-622867D01*
G01Y-623800D02*
X604833Y-623267D01*
X604233Y-623000D01*
X603533Y-622867D01*
X602833Y-623133D01*
X602233Y-623667D01*
X601833Y-624467D01*
X601633Y-625533D01*
X601833Y-626600D01*
X602233Y-627400D01*
X602833Y-627933D01*
X603533Y-628200D01*
X604233Y-628067D01*
X604833Y-627667D01*
X605233Y-627134D01*
G01X609733Y-628200D02*
Y-622867D01*
G01Y-624200D02*
X610133Y-623533D01*
X610733Y-623000D01*
X611533Y-622867D01*
X612233Y-623000D01*
X612833Y-623533D01*
X613133Y-624467D01*
Y-628200D01*
G01X627433D02*
Y-620200D01*
X626233Y-621800D01*
G01Y-628200D02*
X628633D01*
G01X640433D02*
Y-622867D01*
G01Y-624333D02*
X640733Y-623667D01*
X641233Y-623133D01*
X641933Y-622867D01*
X642633Y-623133D01*
X643133Y-623667D01*
X643433Y-624333D01*
Y-628200D01*
G01Y-624333D02*
X643733Y-623667D01*
X644233Y-623133D01*
X644933Y-622867D01*
X645633Y-623133D01*
X646133Y-623667D01*
X646433Y-624467D01*
Y-628200D01*
G01X651433Y-622867D02*
Y-628200D01*
G01Y-620733D02*
X651233Y-620600D01*
Y-620333D01*
X651433Y-620200D01*
X651633Y-620333D01*
Y-620600D01*
X651433Y-620733D01*
G01X657933Y-627267D02*
X658433Y-627800D01*
X659133Y-628200D01*
X659733D01*
X660333Y-627933D01*
X660733Y-627533D01*
X660933Y-627000D01*
X660833Y-626200D01*
X660433Y-625800D01*
X658633Y-625000D01*
X658233Y-624067D01*
X658433Y-623400D01*
X658833Y-623000D01*
X659433Y-622867D01*
X660033Y-623000D01*
X660633Y-623400D01*
G01X667233Y-629667D02*
X667633Y-627933D01*
G01X681633Y-630867D02*
Y-622867D01*
G01Y-624067D02*
X682133Y-623400D01*
X682633Y-623000D01*
X683433Y-622867D01*
X684133Y-623000D01*
X684833Y-623667D01*
X685133Y-624600D01*
X685233Y-625533D01*
X685133Y-626467D01*
X684833Y-627400D01*
X684233Y-627933D01*
X683433Y-628200D01*
X682733Y-628067D01*
X682033Y-627667D01*
X681633Y-627134D01*
G01X691433Y-628200D02*
Y-620200D01*
G01X697933Y-624600D02*
X701133D01*
X700833Y-623667D01*
X700333Y-623133D01*
X699633Y-622867D01*
X698933Y-623000D01*
X698333Y-623400D01*
X697933Y-624333D01*
X697733Y-625134D01*
Y-625933D01*
X697933Y-626733D01*
X698433Y-627533D01*
X699033Y-628067D01*
X699733Y-628200D01*
X700433Y-627933D01*
X701133Y-627134D01*
G01X709233Y-628200D02*
Y-622867D01*
G01Y-623800D02*
X708833Y-623267D01*
X708233Y-623000D01*
X707533Y-622867D01*
X706833Y-623133D01*
X706233Y-623667D01*
X705833Y-624467D01*
X705633Y-625533D01*
X705833Y-626600D01*
X706233Y-627400D01*
X706833Y-627933D01*
X707533Y-628200D01*
X708233Y-628067D01*
X708833Y-627667D01*
X709233Y-627134D01*
G01X713933Y-627267D02*
X714433Y-627800D01*
X715133Y-628200D01*
X715733D01*
X716333Y-627933D01*
X716733Y-627533D01*
X716933Y-627000D01*
X716833Y-626200D01*
X716433Y-625800D01*
X714633Y-625000D01*
X714233Y-624067D01*
X714433Y-623400D01*
X714833Y-623000D01*
X715433Y-622867D01*
X716033Y-623000D01*
X716633Y-623400D01*
G01X721933Y-624600D02*
X725133D01*
X724833Y-623667D01*
X724333Y-623133D01*
X723633Y-622867D01*
X722933Y-623000D01*
X722333Y-623400D01*
X721933Y-624333D01*
X721733Y-625134D01*
Y-625933D01*
X721933Y-626733D01*
X722433Y-627533D01*
X723033Y-628067D01*
X723733Y-628200D01*
X724433Y-627933D01*
X725133Y-627134D01*
G01X739433Y-622867D02*
Y-628200D01*
G01Y-620733D02*
X739233Y-620600D01*
Y-620333D01*
X739433Y-620200D01*
X739633Y-620333D01*
Y-620600D01*
X739433Y-620733D01*
G01X745933Y-627267D02*
X746433Y-627800D01*
X747133Y-628200D01*
X747733D01*
X748333Y-627933D01*
X748733Y-627533D01*
X748933Y-627000D01*
X748833Y-626200D01*
X748433Y-625800D01*
X746633Y-625000D01*
X746233Y-624067D01*
X746433Y-623400D01*
X746833Y-623000D01*
X747433Y-622867D01*
X748033Y-623000D01*
X748633Y-623400D01*
G01X753933Y-627267D02*
X754433Y-627800D01*
X755133Y-628200D01*
X755733D01*
X756333Y-627933D01*
X756733Y-627533D01*
X756933Y-627000D01*
X756833Y-626200D01*
X756433Y-625800D01*
X754633Y-625000D01*
X754233Y-624067D01*
X754433Y-623400D01*
X754833Y-623000D01*
X755433Y-622867D01*
X756033Y-623000D01*
X756633Y-623400D01*
G01X761733Y-622867D02*
Y-626600D01*
X762133Y-627533D01*
X762733Y-628067D01*
X763433Y-628200D01*
X764133Y-628067D01*
X764733Y-627533D01*
X765133Y-626600D01*
G01Y-628200D02*
Y-622867D01*
G01X769933Y-624600D02*
X773133D01*
X772833Y-623667D01*
X772333Y-623133D01*
X771633Y-622867D01*
X770933Y-623000D01*
X770333Y-623400D01*
X769933Y-624333D01*
X769733Y-625134D01*
Y-625933D01*
X769933Y-626733D01*
X770433Y-627533D01*
X771033Y-628067D01*
X771733Y-628200D01*
X772433Y-627933D01*
X773133Y-627134D01*
G01X785933Y-624600D02*
X789133D01*
X788833Y-623667D01*
X788333Y-623133D01*
X787633Y-622867D01*
X786933Y-623000D01*
X786333Y-623400D01*
X785933Y-624333D01*
X785733Y-625134D01*
Y-625933D01*
X785933Y-626733D01*
X786433Y-627533D01*
X787033Y-628067D01*
X787733Y-628200D01*
X788433Y-627933D01*
X789133Y-627134D01*
G01X793733Y-628200D02*
Y-622867D01*
G01Y-624200D02*
X794133Y-623533D01*
X794733Y-623000D01*
X795533Y-622867D01*
X796233Y-623000D01*
X796833Y-623533D01*
X797133Y-624467D01*
Y-628200D01*
G01X802033Y-630200D02*
X802733Y-630733D01*
X803533Y-630867D01*
X804233Y-630733D01*
X804833Y-630067D01*
X805233Y-629133D01*
Y-622867D01*
G01Y-623933D02*
X804833Y-623400D01*
X804233Y-623000D01*
X803533Y-622867D01*
X802733Y-623133D01*
X802233Y-623667D01*
X801833Y-624600D01*
X801633Y-625533D01*
X801733Y-626333D01*
X802133Y-627267D01*
X802733Y-627933D01*
X803533Y-628200D01*
X804133Y-628067D01*
X804833Y-627533D01*
X805233Y-627000D01*
G01X811433Y-622867D02*
Y-628200D01*
G01Y-620733D02*
X811233Y-620600D01*
Y-620333D01*
X811433Y-620200D01*
X811633Y-620333D01*
Y-620600D01*
X811433Y-620733D01*
G01X817733Y-628200D02*
Y-622867D01*
G01Y-624200D02*
X818133Y-623533D01*
X818733Y-623000D01*
X819533Y-622867D01*
X820233Y-623000D01*
X820833Y-623533D01*
X821133Y-624467D01*
Y-628200D01*
G01X825933Y-624600D02*
X829133D01*
X828833Y-623667D01*
X828333Y-623133D01*
X827633Y-622867D01*
X826933Y-623000D01*
X826333Y-623400D01*
X825933Y-624333D01*
X825733Y-625134D01*
Y-625933D01*
X825933Y-626733D01*
X826433Y-627533D01*
X827033Y-628067D01*
X827733Y-628200D01*
X828433Y-627933D01*
X829133Y-627134D01*
G01X833933Y-624600D02*
X837133D01*
X836833Y-623667D01*
X836333Y-623133D01*
X835633Y-622867D01*
X834933Y-623000D01*
X834333Y-623400D01*
X833933Y-624333D01*
X833733Y-625134D01*
Y-625933D01*
X833933Y-626733D01*
X834433Y-627533D01*
X835033Y-628067D01*
X835733Y-628200D01*
X836433Y-627933D01*
X837133Y-627134D01*
G01X842033Y-628200D02*
Y-622867D01*
G01Y-623933D02*
X842533Y-623400D01*
X843033Y-623000D01*
X843733Y-622867D01*
X844233Y-623000D01*
X844833Y-623400D01*
G01X851433Y-622867D02*
Y-628200D01*
G01Y-620733D02*
X851233Y-620600D01*
Y-620333D01*
X851433Y-620200D01*
X851633Y-620333D01*
Y-620600D01*
X851433Y-620733D01*
G01X857733Y-628200D02*
Y-622867D01*
G01Y-624200D02*
X858133Y-623533D01*
X858733Y-623000D01*
X859533Y-622867D01*
X860233Y-623000D01*
X860833Y-623533D01*
X861133Y-624467D01*
Y-628200D01*
G01X866033Y-630200D02*
X866733Y-630733D01*
X867533Y-630867D01*
X868233Y-630733D01*
X868833Y-630067D01*
X869233Y-629133D01*
Y-622867D01*
G01Y-623933D02*
X868833Y-623400D01*
X868233Y-623000D01*
X867533Y-622867D01*
X866733Y-623133D01*
X866233Y-623667D01*
X865833Y-624600D01*
X865633Y-625533D01*
X865733Y-626333D01*
X866133Y-627267D01*
X866733Y-627933D01*
X867533Y-628200D01*
X868133Y-628067D01*
X868833Y-627533D01*
X869233Y-627000D01*
G01X885233Y-630867D02*
Y-622867D01*
G01Y-624067D02*
X884733Y-623400D01*
X884133Y-623000D01*
X883433Y-622867D01*
X882833Y-623000D01*
X882133Y-623667D01*
X881733Y-624600D01*
X881633Y-625533D01*
X881733Y-626467D01*
X882133Y-627400D01*
X882833Y-628067D01*
X883433Y-628200D01*
X884133Y-628067D01*
X884733Y-627667D01*
X885233Y-627000D01*
G01X889733Y-622867D02*
Y-626600D01*
X890133Y-627533D01*
X890733Y-628067D01*
X891433Y-628200D01*
X892133Y-628067D01*
X892733Y-627533D01*
X893133Y-626600D01*
G01Y-628200D02*
Y-622867D01*
G01X897933Y-624600D02*
X901133D01*
X900833Y-623667D01*
X900333Y-623133D01*
X899633Y-622867D01*
X898933Y-623000D01*
X898333Y-623400D01*
X897933Y-624333D01*
X897733Y-625134D01*
Y-625933D01*
X897933Y-626733D01*
X898433Y-627533D01*
X899033Y-628067D01*
X899733Y-628200D01*
X900433Y-627933D01*
X901133Y-627134D01*
G01X906033Y-628200D02*
Y-622867D01*
G01Y-623933D02*
X906533Y-623400D01*
X907033Y-623000D01*
X907733Y-622867D01*
X908233Y-623000D01*
X908833Y-623400D01*
G01X913333Y-630600D02*
X913933Y-630867D01*
X914733Y-630600D01*
X915233Y-630067D01*
X915633Y-629400D01*
X916233Y-627267D01*
X917533Y-622867D01*
G01X914333D02*
X916233Y-627267D01*
G01X923433Y-628467D02*
X923233Y-628333D01*
Y-628067D01*
X923433Y-627933D01*
X923633Y-628067D01*
Y-628333D01*
X923433Y-628467D01*
G01X474033Y-640000D02*
Y-632000D01*
X477833D01*
G01X476433Y-635867D02*
X474033D01*
G01X483933Y-640000D02*
X483333Y-639867D01*
X482733Y-639333D01*
X482333Y-638400D01*
X482133Y-637333D01*
X482333Y-636267D01*
X482733Y-635333D01*
X483333Y-634800D01*
X483933Y-634667D01*
X484533Y-634800D01*
X485133Y-635333D01*
X485533Y-636267D01*
X485633Y-637333D01*
X485533Y-638400D01*
X485133Y-639333D01*
X484533Y-639867D01*
X483933Y-640000D01*
G01X490533D02*
Y-634667D01*
G01Y-635733D02*
X491033Y-635200D01*
X491533Y-634800D01*
X492233Y-634667D01*
X492733Y-634800D01*
X493333Y-635200D01*
G01X506433Y-636400D02*
X509633D01*
X509333Y-635467D01*
X508833Y-634933D01*
X508133Y-634667D01*
X507433Y-634800D01*
X506833Y-635200D01*
X506433Y-636133D01*
X506233Y-636934D01*
Y-637733D01*
X506433Y-638533D01*
X506933Y-639333D01*
X507533Y-639867D01*
X508233Y-640000D01*
X508933Y-639733D01*
X509633Y-638934D01*
G01X514433Y-634667D02*
X517433Y-640000D01*
G01Y-634667D02*
X514433Y-640000D01*
G01X525733D02*
Y-634667D01*
G01Y-635600D02*
X525333Y-635067D01*
X524733Y-634800D01*
X524033Y-634667D01*
X523333Y-634933D01*
X522733Y-635467D01*
X522333Y-636267D01*
X522133Y-637333D01*
X522333Y-638400D01*
X522733Y-639200D01*
X523333Y-639733D01*
X524033Y-640000D01*
X524733Y-639867D01*
X525333Y-639467D01*
X525733Y-638934D01*
G01X528933Y-640000D02*
Y-634667D01*
G01Y-636133D02*
X529233Y-635467D01*
X529733Y-634933D01*
X530433Y-634667D01*
X531133Y-634933D01*
X531633Y-635467D01*
X531933Y-636133D01*
Y-640000D01*
G01Y-636133D02*
X532233Y-635467D01*
X532733Y-634933D01*
X533433Y-634667D01*
X534133Y-634933D01*
X534633Y-635467D01*
X534933Y-636267D01*
Y-640000D01*
G01X538133Y-642667D02*
Y-634667D01*
G01Y-635867D02*
X538633Y-635200D01*
X539133Y-634800D01*
X539933Y-634667D01*
X540633Y-634800D01*
X541333Y-635467D01*
X541633Y-636400D01*
X541733Y-637333D01*
X541633Y-638267D01*
X541333Y-639200D01*
X540733Y-639733D01*
X539933Y-640000D01*
X539233Y-639867D01*
X538533Y-639467D01*
X538133Y-638934D01*
G01X547933Y-640000D02*
Y-632000D01*
G01X554433Y-636400D02*
X557633D01*
X557333Y-635467D01*
X556833Y-634933D01*
X556133Y-634667D01*
X555433Y-634800D01*
X554833Y-635200D01*
X554433Y-636133D01*
X554233Y-636934D01*
Y-637733D01*
X554433Y-638533D01*
X554933Y-639333D01*
X555533Y-639867D01*
X556233Y-640000D01*
X556933Y-639733D01*
X557633Y-638934D01*
G01X563933Y-640267D02*
X563733Y-640133D01*
Y-639867D01*
X563933Y-639733D01*
X564133Y-639867D01*
Y-640133D01*
X563933Y-640267D01*
G01Y-636667D02*
X563733Y-636533D01*
Y-636267D01*
X563933Y-636133D01*
X564133Y-636267D01*
Y-636533D01*
X563933Y-636667D01*
G01X577833Y-640000D02*
Y-632000D01*
G01X582033D02*
Y-640000D01*
G01Y-636000D02*
X577833D01*
G01X587933Y-640000D02*
X587333Y-639867D01*
X586733Y-639333D01*
X586333Y-638400D01*
X586133Y-637333D01*
X586333Y-636267D01*
X586733Y-635333D01*
X587333Y-634800D01*
X587933Y-634667D01*
X588533Y-634800D01*
X589133Y-635333D01*
X589533Y-636267D01*
X589633Y-637333D01*
X589533Y-638400D01*
X589133Y-639333D01*
X588533Y-639867D01*
X587933Y-640000D01*
G01X595933D02*
Y-632000D01*
G01X602433Y-636400D02*
X605633D01*
X605333Y-635467D01*
X604833Y-634933D01*
X604133Y-634667D01*
X603433Y-634800D01*
X602833Y-635200D01*
X602433Y-636133D01*
X602233Y-636934D01*
Y-637733D01*
X602433Y-638533D01*
X602933Y-639333D01*
X603533Y-639867D01*
X604233Y-640000D01*
X604933Y-639733D01*
X605633Y-638934D01*
G01X617733Y-640000D02*
Y-632000D01*
X619733D01*
X620533Y-632400D01*
X621133Y-632933D01*
X621633Y-633733D01*
X622033Y-634667D01*
X622133Y-636000D01*
X622033Y-637333D01*
X621633Y-638267D01*
X621133Y-639067D01*
X620533Y-639600D01*
X619733Y-640000D01*
X617733D01*
G01X627933Y-634667D02*
Y-640000D01*
G01Y-632533D02*
X627733Y-632400D01*
Y-632133D01*
X627933Y-632000D01*
X628133Y-632133D01*
Y-632400D01*
X627933Y-632533D01*
G01X637733Y-640000D02*
Y-634667D01*
G01Y-635600D02*
X637333Y-635067D01*
X636733Y-634800D01*
X636033Y-634667D01*
X635333Y-634933D01*
X634733Y-635467D01*
X634333Y-636267D01*
X634133Y-637333D01*
X634333Y-638400D01*
X634733Y-639200D01*
X635333Y-639733D01*
X636033Y-640000D01*
X636733Y-639867D01*
X637333Y-639467D01*
X637733Y-638934D01*
G01X643933Y-640267D02*
X643733Y-640133D01*
Y-639867D01*
X643933Y-639733D01*
X644133Y-639867D01*
Y-640133D01*
X643933Y-640267D01*
G01X649733Y-638400D02*
X650333Y-639333D01*
X651133Y-639867D01*
X652033Y-640000D01*
X652833Y-639867D01*
X653633Y-639200D01*
X654133Y-638400D01*
X654233Y-637600D01*
X654033Y-636667D01*
X653333Y-636000D01*
X652633Y-635733D01*
X651733D01*
G01X652633D02*
X653233Y-635333D01*
X653733Y-634667D01*
X653933Y-633867D01*
X653733Y-633067D01*
X653233Y-632400D01*
X652333Y-632000D01*
X651433Y-632133D01*
X650533Y-632667D01*
G01X659933Y-640267D02*
X659733Y-640133D01*
Y-639867D01*
X659933Y-639733D01*
X660133Y-639867D01*
Y-640133D01*
X659933Y-640267D01*
G01X667933Y-640000D02*
Y-632000D01*
X666733Y-633600D01*
G01Y-640000D02*
X669133D01*
G01X675933D02*
X676633Y-639867D01*
X677433Y-639467D01*
X677933Y-638800D01*
X678133Y-637867D01*
X677933Y-636934D01*
X677333Y-636133D01*
X676433Y-635733D01*
X675433D01*
X674833Y-635467D01*
X674333Y-634800D01*
X674133Y-633867D01*
X674433Y-632933D01*
X675133Y-632267D01*
X675933Y-632000D01*
X676733Y-632267D01*
X677433Y-632933D01*
X677733Y-633867D01*
X677533Y-634800D01*
X677033Y-635467D01*
X676433Y-635733D01*
X675433D01*
X674533Y-636133D01*
X673933Y-636934D01*
X673733Y-637867D01*
X673933Y-638800D01*
X674433Y-639467D01*
X675233Y-639867D01*
X675933Y-640000D01*
G01X680933D02*
Y-634667D01*
G01Y-636133D02*
X681233Y-635467D01*
X681733Y-634933D01*
X682433Y-634667D01*
X683133Y-634933D01*
X683633Y-635467D01*
X683933Y-636133D01*
Y-640000D01*
G01Y-636133D02*
X684233Y-635467D01*
X684733Y-634933D01*
X685433Y-634667D01*
X686133Y-634933D01*
X686633Y-635467D01*
X686933Y-636267D01*
Y-640000D01*
G01X688933D02*
Y-634667D01*
G01Y-636133D02*
X689233Y-635467D01*
X689733Y-634933D01*
X690433Y-634667D01*
X691133Y-634933D01*
X691633Y-635467D01*
X691933Y-636133D01*
Y-640000D01*
G01Y-636133D02*
X692233Y-635467D01*
X692733Y-634933D01*
X693433Y-634667D01*
X694133Y-634933D01*
X694633Y-635467D01*
X694933Y-636267D01*
Y-640000D01*
G01X707933Y-634667D02*
Y-640000D01*
G01Y-632533D02*
X707733Y-632400D01*
Y-632133D01*
X707933Y-632000D01*
X708133Y-632133D01*
Y-632400D01*
X707933Y-632533D01*
G01X714433Y-639067D02*
X714933Y-639600D01*
X715633Y-640000D01*
X716233D01*
X716833Y-639733D01*
X717233Y-639333D01*
X717433Y-638800D01*
X717333Y-638000D01*
X716933Y-637600D01*
X715133Y-636800D01*
X714733Y-635867D01*
X714933Y-635200D01*
X715333Y-634800D01*
X715933Y-634667D01*
X716533Y-634800D01*
X717133Y-635200D01*
G01X728933Y-640000D02*
Y-634667D01*
G01Y-636133D02*
X729233Y-635467D01*
X729733Y-634933D01*
X730433Y-634667D01*
X731133Y-634933D01*
X731633Y-635467D01*
X731933Y-636133D01*
Y-640000D01*
G01Y-636133D02*
X732233Y-635467D01*
X732733Y-634933D01*
X733433Y-634667D01*
X734133Y-634933D01*
X734633Y-635467D01*
X734933Y-636267D01*
Y-640000D01*
G01X741733D02*
Y-634667D01*
G01Y-635600D02*
X741333Y-635067D01*
X740733Y-634800D01*
X740033Y-634667D01*
X739333Y-634933D01*
X738733Y-635467D01*
X738333Y-636267D01*
X738133Y-637333D01*
X738333Y-638400D01*
X738733Y-639200D01*
X739333Y-639733D01*
X740033Y-640000D01*
X740733Y-639867D01*
X741333Y-639467D01*
X741733Y-638934D01*
G01X746533Y-640000D02*
Y-634667D01*
G01Y-635733D02*
X747033Y-635200D01*
X747533Y-634800D01*
X748233Y-634667D01*
X748733Y-634800D01*
X749333Y-635200D01*
G01X754233Y-640000D02*
Y-632000D01*
G01X757433Y-634667D02*
X754233Y-637733D01*
G01X755533Y-636533D02*
X757633Y-640000D01*
G01X762433Y-636400D02*
X765633D01*
X765333Y-635467D01*
X764833Y-634933D01*
X764133Y-634667D01*
X763433Y-634800D01*
X762833Y-635200D01*
X762433Y-636133D01*
X762233Y-636934D01*
Y-637733D01*
X762433Y-638533D01*
X762933Y-639333D01*
X763533Y-639867D01*
X764233Y-640000D01*
X764933Y-639733D01*
X765633Y-638934D01*
G01X773733Y-632000D02*
Y-640000D01*
G01Y-638800D02*
X773333Y-639467D01*
X772733Y-639867D01*
X772033Y-640000D01*
X771233Y-639733D01*
X770633Y-639067D01*
X770233Y-638267D01*
X770133Y-637333D01*
X770233Y-636400D01*
X770633Y-635600D01*
X771233Y-634933D01*
X772033Y-634667D01*
X772733Y-634800D01*
X773233Y-635067D01*
X773733Y-635600D01*
G01X787933Y-634667D02*
Y-640000D01*
G01Y-632533D02*
X787733Y-632400D01*
Y-632133D01*
X787933Y-632000D01*
X788133Y-632133D01*
Y-632400D01*
X787933Y-632533D01*
G01X794233Y-640000D02*
Y-634667D01*
G01Y-636000D02*
X794633Y-635333D01*
X795233Y-634800D01*
X796033Y-634667D01*
X796733Y-634800D01*
X797333Y-635333D01*
X797633Y-636267D01*
Y-640000D01*
G01X808933D02*
Y-634667D01*
G01Y-636133D02*
X809233Y-635467D01*
X809733Y-634933D01*
X810433Y-634667D01*
X811133Y-634933D01*
X811633Y-635467D01*
X811933Y-636133D01*
Y-640000D01*
G01Y-636133D02*
X812233Y-635467D01*
X812733Y-634933D01*
X813433Y-634667D01*
X814133Y-634933D01*
X814633Y-635467D01*
X814933Y-636267D01*
Y-640000D01*
G01X818433Y-636400D02*
X821633D01*
X821333Y-635467D01*
X820833Y-634933D01*
X820133Y-634667D01*
X819433Y-634800D01*
X818833Y-635200D01*
X818433Y-636133D01*
X818233Y-636934D01*
Y-637733D01*
X818433Y-638533D01*
X818933Y-639333D01*
X819533Y-639867D01*
X820233Y-640000D01*
X820933Y-639733D01*
X821633Y-638934D01*
G01X829533Y-635333D02*
X828833Y-634800D01*
X828233Y-634667D01*
X827433Y-634933D01*
X826833Y-635467D01*
X826433Y-636400D01*
X826333Y-637333D01*
X826433Y-638267D01*
X826833Y-639067D01*
X827433Y-639733D01*
X828233Y-640000D01*
X828933Y-639733D01*
X829533Y-639200D01*
G01X834233Y-640000D02*
Y-632000D01*
G01Y-635867D02*
X834733Y-635200D01*
X835233Y-634800D01*
X836033Y-634667D01*
X836633Y-634800D01*
X837333Y-635333D01*
X837633Y-636133D01*
Y-640000D01*
G01X845733D02*
Y-634667D01*
G01Y-635600D02*
X845333Y-635067D01*
X844733Y-634800D01*
X844033Y-634667D01*
X843333Y-634933D01*
X842733Y-635467D01*
X842333Y-636267D01*
X842133Y-637333D01*
X842333Y-638400D01*
X842733Y-639200D01*
X843333Y-639733D01*
X844033Y-640000D01*
X844733Y-639867D01*
X845333Y-639467D01*
X845733Y-638934D01*
G01X850233Y-640000D02*
Y-634667D01*
G01Y-636000D02*
X850633Y-635333D01*
X851233Y-634800D01*
X852033Y-634667D01*
X852733Y-634800D01*
X853333Y-635333D01*
X853633Y-636267D01*
Y-640000D01*
G01X859933Y-634667D02*
Y-640000D01*
G01Y-632533D02*
X859733Y-632400D01*
Y-632133D01*
X859933Y-632000D01*
X860133Y-632133D01*
Y-632400D01*
X859933Y-632533D01*
G01X869533Y-635333D02*
X868833Y-634800D01*
X868233Y-634667D01*
X867433Y-634933D01*
X866833Y-635467D01*
X866433Y-636400D01*
X866333Y-637333D01*
X866433Y-638267D01*
X866833Y-639067D01*
X867433Y-639733D01*
X868233Y-640000D01*
X868933Y-639733D01*
X869533Y-639200D01*
G01X877733Y-640000D02*
Y-634667D01*
G01Y-635600D02*
X877333Y-635067D01*
X876733Y-634800D01*
X876033Y-634667D01*
X875333Y-634933D01*
X874733Y-635467D01*
X874333Y-636267D01*
X874133Y-637333D01*
X874333Y-638400D01*
X874733Y-639200D01*
X875333Y-639733D01*
X876033Y-640000D01*
X876733Y-639867D01*
X877333Y-639467D01*
X877733Y-638934D01*
G01X883933Y-640000D02*
Y-632000D01*
G01X901733D02*
Y-640000D01*
G01Y-638800D02*
X901333Y-639467D01*
X900733Y-639867D01*
X900033Y-640000D01*
X899233Y-639733D01*
X898633Y-639067D01*
X898233Y-638267D01*
X898133Y-637333D01*
X898233Y-636400D01*
X898633Y-635600D01*
X899233Y-634933D01*
X900033Y-634667D01*
X900733Y-634800D01*
X901233Y-635067D01*
X901733Y-635600D01*
G01X906533Y-640000D02*
Y-634667D01*
G01Y-635733D02*
X907033Y-635200D01*
X907533Y-634800D01*
X908233Y-634667D01*
X908733Y-634800D01*
X909333Y-635200D01*
G01X917733Y-640000D02*
Y-634667D01*
G01Y-635600D02*
X917333Y-635067D01*
X916733Y-634800D01*
X916033Y-634667D01*
X915333Y-634933D01*
X914733Y-635467D01*
X914333Y-636267D01*
X914133Y-637333D01*
X914333Y-638400D01*
X914733Y-639200D01*
X915333Y-639733D01*
X916033Y-640000D01*
X916733Y-639867D01*
X917333Y-639467D01*
X917733Y-638934D01*
G01X921433Y-634667D02*
X922633Y-640000D01*
X923933Y-634667D01*
X925233Y-640000D01*
X926433Y-634667D01*
G01X931933D02*
Y-640000D01*
G01Y-632533D02*
X931733Y-632400D01*
Y-632133D01*
X931933Y-632000D01*
X932133Y-632133D01*
Y-632400D01*
X931933Y-632533D01*
G01X938233Y-640000D02*
Y-634667D01*
G01Y-636000D02*
X938633Y-635333D01*
X939233Y-634800D01*
X940033Y-634667D01*
X940733Y-634800D01*
X941333Y-635333D01*
X941633Y-636267D01*
Y-640000D01*
G01X946533Y-642000D02*
X947233Y-642533D01*
X948033Y-642667D01*
X948733Y-642533D01*
X949333Y-641867D01*
X949733Y-640933D01*
Y-634667D01*
G01Y-635733D02*
X949333Y-635200D01*
X948733Y-634800D01*
X948033Y-634667D01*
X947233Y-634933D01*
X946733Y-635467D01*
X946333Y-636400D01*
X946133Y-637333D01*
X946233Y-638133D01*
X946633Y-639067D01*
X947233Y-639733D01*
X948033Y-640000D01*
X948633Y-639867D01*
X949333Y-639333D01*
X949733Y-638800D01*
G01X965733Y-640000D02*
Y-634667D01*
G01Y-635600D02*
X965333Y-635067D01*
X964733Y-634800D01*
X964033Y-634667D01*
X963333Y-634933D01*
X962733Y-635467D01*
X962333Y-636267D01*
X962133Y-637333D01*
X962333Y-638400D01*
X962733Y-639200D01*
X963333Y-639733D01*
X964033Y-640000D01*
X964733Y-639867D01*
X965333Y-639467D01*
X965733Y-638934D01*
G01X970233Y-640000D02*
Y-634667D01*
G01Y-636000D02*
X970633Y-635333D01*
X971233Y-634800D01*
X972033Y-634667D01*
X972733Y-634800D01*
X973333Y-635333D01*
X973633Y-636267D01*
Y-640000D01*
G01X981733Y-632000D02*
Y-640000D01*
G01Y-638800D02*
X981333Y-639467D01*
X980733Y-639867D01*
X980033Y-640000D01*
X979233Y-639733D01*
X978633Y-639067D01*
X978233Y-638267D01*
X978133Y-637333D01*
X978233Y-636400D01*
X978633Y-635600D01*
X979233Y-634933D01*
X980033Y-634667D01*
X980733Y-634800D01*
X981233Y-635067D01*
X981733Y-635600D01*
G01X994233Y-640000D02*
Y-632000D01*
G01Y-635867D02*
X994733Y-635200D01*
X995233Y-634800D01*
X996033Y-634667D01*
X996633Y-634800D01*
X997333Y-635333D01*
X997633Y-636133D01*
Y-640000D01*
G01X1003933D02*
X1003333Y-639867D01*
X1002733Y-639333D01*
X1002333Y-638400D01*
X1002133Y-637333D01*
X1002333Y-636267D01*
X1002733Y-635333D01*
X1003333Y-634800D01*
X1003933Y-634667D01*
X1004533Y-634800D01*
X1005133Y-635333D01*
X1005533Y-636267D01*
X1005633Y-637333D01*
X1005533Y-638400D01*
X1005133Y-639333D01*
X1004533Y-639867D01*
X1003933Y-640000D01*
G01X1011933D02*
Y-632000D01*
G01X1018433Y-636400D02*
X1021633D01*
X1021333Y-635467D01*
X1020833Y-634933D01*
X1020133Y-634667D01*
X1019433Y-634800D01*
X1018833Y-635200D01*
X1018433Y-636133D01*
X1018233Y-636934D01*
Y-637733D01*
X1018433Y-638533D01*
X1018933Y-639333D01*
X1019533Y-639867D01*
X1020233Y-640000D01*
X1020933Y-639733D01*
X1021633Y-638934D01*
G01X1033733Y-640000D02*
Y-632000D01*
X1035733D01*
X1036533Y-632400D01*
X1037133Y-632933D01*
X1037633Y-633733D01*
X1038033Y-634667D01*
X1038133Y-636000D01*
X1038033Y-637333D01*
X1037633Y-638267D01*
X1037133Y-639067D01*
X1036533Y-639600D01*
X1035733Y-640000D01*
X1033733D01*
G01X1043933Y-634667D02*
Y-640000D01*
G01Y-632533D02*
X1043733Y-632400D01*
Y-632133D01*
X1043933Y-632000D01*
X1044133Y-632133D01*
Y-632400D01*
X1043933Y-632533D01*
G01X1053733Y-640000D02*
Y-634667D01*
G01Y-635600D02*
X1053333Y-635067D01*
X1052733Y-634800D01*
X1052033Y-634667D01*
X1051333Y-634933D01*
X1050733Y-635467D01*
X1050333Y-636267D01*
X1050133Y-637333D01*
X1050333Y-638400D01*
X1050733Y-639200D01*
X1051333Y-639733D01*
X1052033Y-640000D01*
X1052733Y-639867D01*
X1053333Y-639467D01*
X1053733Y-638934D01*
G01X1059933Y-640267D02*
X1059733Y-640133D01*
Y-639867D01*
X1059933Y-639733D01*
X1060133Y-639867D01*
Y-640133D01*
X1059933Y-640267D01*
G01X1075933Y-640000D02*
Y-632000D01*
X1074733Y-633600D01*
G01Y-640000D02*
X1077133D01*
G01X1082033Y-633333D02*
X1082633Y-632533D01*
X1083333Y-632133D01*
X1084133Y-632000D01*
X1085133Y-632267D01*
X1085833Y-632933D01*
X1086033Y-633733D01*
X1085933Y-634534D01*
X1085533Y-635200D01*
X1083533Y-636533D01*
X1082633Y-637467D01*
X1082033Y-638800D01*
X1081833Y-640000D01*
X1086033D01*
G01X1090033Y-636667D02*
X1090733Y-635733D01*
X1091333Y-635200D01*
X1092133Y-634933D01*
X1092833Y-635200D01*
X1093333Y-635733D01*
X1093733Y-636533D01*
X1093833Y-637467D01*
X1093733Y-638267D01*
X1093333Y-639067D01*
X1092733Y-639733D01*
X1092033Y-640000D01*
X1091233Y-639733D01*
X1090533Y-638934D01*
X1090133Y-637733D01*
X1090033Y-636400D01*
X1090233Y-634667D01*
X1090533Y-633733D01*
X1091033Y-632800D01*
X1091733Y-632133D01*
X1092433Y-632000D01*
X1093133Y-632267D01*
X1093633Y-632933D01*
G01X1096933Y-640000D02*
Y-634667D01*
G01Y-636133D02*
X1097233Y-635467D01*
X1097733Y-634933D01*
X1098433Y-634667D01*
X1099133Y-634933D01*
X1099633Y-635467D01*
X1099933Y-636133D01*
Y-640000D01*
G01Y-636133D02*
X1100233Y-635467D01*
X1100733Y-634933D01*
X1101433Y-634667D01*
X1102133Y-634933D01*
X1102633Y-635467D01*
X1102933Y-636267D01*
Y-640000D01*
G01X1107933Y-634667D02*
Y-640000D01*
G01Y-632533D02*
X1107733Y-632400D01*
Y-632133D01*
X1107933Y-632000D01*
X1108133Y-632133D01*
Y-632400D01*
X1107933Y-632533D01*
G01X1115933Y-640000D02*
Y-632000D01*
G01X1131933Y-634667D02*
Y-640000D01*
G01Y-632533D02*
X1131733Y-632400D01*
Y-632133D01*
X1131933Y-632000D01*
X1132133Y-632133D01*
Y-632400D01*
X1131933Y-632533D01*
G01X1138433Y-639067D02*
X1138933Y-639600D01*
X1139633Y-640000D01*
X1140233D01*
X1140833Y-639733D01*
X1141233Y-639333D01*
X1141433Y-638800D01*
X1141333Y-638000D01*
X1140933Y-637600D01*
X1139133Y-636800D01*
X1138733Y-635867D01*
X1138933Y-635200D01*
X1139333Y-634800D01*
X1139933Y-634667D01*
X1140533Y-634800D01*
X1141133Y-635200D01*
G01X1152933Y-640000D02*
Y-634667D01*
G01Y-636133D02*
X1153233Y-635467D01*
X1153733Y-634933D01*
X1154433Y-634667D01*
X1155133Y-634933D01*
X1155633Y-635467D01*
X1155933Y-636133D01*
Y-640000D01*
G01Y-636133D02*
X1156233Y-635467D01*
X1156733Y-634933D01*
X1157433Y-634667D01*
X1158133Y-634933D01*
X1158633Y-635467D01*
X1158933Y-636267D01*
Y-640000D01*
G01X1165733D02*
Y-634667D01*
G01Y-635600D02*
X1165333Y-635067D01*
X1164733Y-634800D01*
X1164033Y-634667D01*
X1163333Y-634933D01*
X1162733Y-635467D01*
X1162333Y-636267D01*
X1162133Y-637333D01*
X1162333Y-638400D01*
X1162733Y-639200D01*
X1163333Y-639733D01*
X1164033Y-640000D01*
X1164733Y-639867D01*
X1165333Y-639467D01*
X1165733Y-638934D01*
G01X1170533Y-640000D02*
Y-634667D01*
G01Y-635733D02*
X1171033Y-635200D01*
X1171533Y-634800D01*
X1172233Y-634667D01*
X1172733Y-634800D01*
X1173333Y-635200D01*
G01X1178233Y-640000D02*
Y-632000D01*
G01X1181433Y-634667D02*
X1178233Y-637733D01*
G01X1179533Y-636533D02*
X1181633Y-640000D01*
G01X1186433Y-636400D02*
X1189633D01*
X1189333Y-635467D01*
X1188833Y-634933D01*
X1188133Y-634667D01*
X1187433Y-634800D01*
X1186833Y-635200D01*
X1186433Y-636133D01*
X1186233Y-636934D01*
Y-637733D01*
X1186433Y-638533D01*
X1186933Y-639333D01*
X1187533Y-639867D01*
X1188233Y-640000D01*
X1188933Y-639733D01*
X1189633Y-638934D01*
G01X1197733Y-632000D02*
Y-640000D01*
G01Y-638800D02*
X1197333Y-639467D01*
X1196733Y-639867D01*
X1196033Y-640000D01*
X1195233Y-639733D01*
X1194633Y-639067D01*
X1194233Y-638267D01*
X1194133Y-637333D01*
X1194233Y-636400D01*
X1194633Y-635600D01*
X1195233Y-634933D01*
X1196033Y-634667D01*
X1196733Y-634800D01*
X1197233Y-635067D01*
X1197733Y-635600D01*
G01X1211933Y-634667D02*
Y-640000D01*
G01Y-632533D02*
X1211733Y-632400D01*
Y-632133D01*
X1211933Y-632000D01*
X1212133Y-632133D01*
Y-632400D01*
X1211933Y-632533D01*
G01X1218233Y-640000D02*
Y-634667D01*
G01Y-636000D02*
X1218633Y-635333D01*
X1219233Y-634800D01*
X1220033Y-634667D01*
X1220733Y-634800D01*
X1221333Y-635333D01*
X1221633Y-636267D01*
Y-640000D01*
G01X1236533Y-636000D02*
X1238533D01*
Y-638400D01*
X1237933Y-639200D01*
X1237233Y-639733D01*
X1236233Y-640000D01*
X1235233Y-639733D01*
X1234533Y-639200D01*
X1233933Y-638400D01*
X1233533Y-637467D01*
X1233333Y-636400D01*
Y-635467D01*
X1233533Y-634667D01*
X1233933Y-633733D01*
X1234533Y-632933D01*
X1235133Y-632400D01*
X1235933Y-632000D01*
X1236633D01*
X1237433Y-632267D01*
X1238033Y-632800D01*
G01X1242433Y-636400D02*
X1245633D01*
X1245333Y-635467D01*
X1244833Y-634933D01*
X1244133Y-634667D01*
X1243433Y-634800D01*
X1242833Y-635200D01*
X1242433Y-636133D01*
X1242233Y-636934D01*
Y-637733D01*
X1242433Y-638533D01*
X1242933Y-639333D01*
X1243533Y-639867D01*
X1244233Y-640000D01*
X1244933Y-639733D01*
X1245633Y-638934D01*
G01X1250533Y-640000D02*
Y-634667D01*
G01Y-635733D02*
X1251033Y-635200D01*
X1251533Y-634800D01*
X1252233Y-634667D01*
X1252733Y-634800D01*
X1253333Y-635200D01*
G01X1258133Y-640000D02*
Y-632000D01*
G01Y-636000D02*
X1258633Y-635200D01*
X1259233Y-634800D01*
X1259833Y-634667D01*
X1260733Y-634933D01*
X1261333Y-635467D01*
X1261733Y-636400D01*
Y-637467D01*
X1261533Y-638533D01*
X1261133Y-639333D01*
X1260433Y-639867D01*
X1259833Y-640000D01*
X1259233Y-639867D01*
X1258633Y-639467D01*
X1258133Y-638800D01*
G01X1266433Y-636400D02*
X1269633D01*
X1269333Y-635467D01*
X1268833Y-634933D01*
X1268133Y-634667D01*
X1267433Y-634800D01*
X1266833Y-635200D01*
X1266433Y-636133D01*
X1266233Y-636934D01*
Y-637733D01*
X1266433Y-638533D01*
X1266933Y-639333D01*
X1267533Y-639867D01*
X1268233Y-640000D01*
X1268933Y-639733D01*
X1269633Y-638934D01*
G01X1274533Y-640000D02*
Y-634667D01*
G01Y-635733D02*
X1275033Y-635200D01*
X1275533Y-634800D01*
X1276233Y-634667D01*
X1276733Y-634800D01*
X1277333Y-635200D01*
G01X1291333Y-640000D02*
Y-633200D01*
X1291533Y-632533D01*
X1291933Y-632133D01*
X1292533Y-632000D01*
X1293133Y-632267D01*
X1293433Y-632933D01*
G01X1292233Y-635200D02*
X1290233D01*
G01X1299933Y-634667D02*
Y-640000D01*
G01Y-632533D02*
X1299733Y-632400D01*
Y-632133D01*
X1299933Y-632000D01*
X1300133Y-632133D01*
Y-632400D01*
X1299933Y-632533D01*
G01X1307933Y-640000D02*
Y-632000D01*
G01X1314433Y-636400D02*
X1317633D01*
X1317333Y-635467D01*
X1316833Y-634933D01*
X1316133Y-634667D01*
X1315433Y-634800D01*
X1314833Y-635200D01*
X1314433Y-636133D01*
X1314233Y-636934D01*
Y-637733D01*
X1314433Y-638533D01*
X1314933Y-639333D01*
X1315533Y-639867D01*
X1316233Y-640000D01*
X1316933Y-639733D01*
X1317633Y-638934D01*
G01X1323933Y-640267D02*
X1323733Y-640133D01*
Y-639867D01*
X1323933Y-639733D01*
X1324133Y-639867D01*
Y-640133D01*
X1323933Y-640267D01*
G01X473833Y-596100D02*
Y-601833D01*
X474233Y-603034D01*
X475033Y-603833D01*
X476033Y-604100D01*
X477033Y-603833D01*
X477833Y-603034D01*
X478233Y-601833D01*
Y-596100D01*
G01X482333Y-604100D02*
Y-598767D01*
G01Y-600100D02*
X482733Y-599433D01*
X483333Y-598900D01*
X484133Y-598767D01*
X484833Y-598900D01*
X485433Y-599433D01*
X485733Y-600367D01*
Y-604100D01*
G01X492033Y-598767D02*
Y-604100D01*
G01Y-596633D02*
X491833Y-596500D01*
Y-596233D01*
X492033Y-596100D01*
X492233Y-596233D01*
Y-596500D01*
X492033Y-596633D01*
G01X500033Y-596100D02*
Y-604100D01*
G01X498633Y-598767D02*
X501433D01*
G01X517633Y-599433D02*
X516933Y-598900D01*
X516333Y-598767D01*
X515533Y-599033D01*
X514933Y-599567D01*
X514533Y-600500D01*
X514433Y-601433D01*
X514533Y-602367D01*
X514933Y-603167D01*
X515533Y-603833D01*
X516333Y-604100D01*
X517033Y-603833D01*
X517633Y-603300D01*
G01X524033Y-604100D02*
X523433Y-603967D01*
X522833Y-603433D01*
X522433Y-602500D01*
X522233Y-601433D01*
X522433Y-600367D01*
X522833Y-599433D01*
X523433Y-598900D01*
X524033Y-598767D01*
X524633Y-598900D01*
X525233Y-599433D01*
X525633Y-600367D01*
X525733Y-601433D01*
X525633Y-602500D01*
X525233Y-603433D01*
X524633Y-603967D01*
X524033Y-604100D01*
G01X530333D02*
Y-598767D01*
G01Y-600100D02*
X530733Y-599433D01*
X531333Y-598900D01*
X532133Y-598767D01*
X532833Y-598900D01*
X533433Y-599433D01*
X533733Y-600367D01*
Y-604100D01*
G01X538233Y-598767D02*
X540033Y-604100D01*
X541833Y-598767D01*
G01X546533Y-600500D02*
X549733D01*
X549433Y-599567D01*
X548933Y-599033D01*
X548233Y-598767D01*
X547533Y-598900D01*
X546933Y-599300D01*
X546533Y-600233D01*
X546333Y-601034D01*
Y-601833D01*
X546533Y-602633D01*
X547033Y-603433D01*
X547633Y-603967D01*
X548333Y-604100D01*
X549033Y-603833D01*
X549733Y-603034D01*
G01X554633Y-604100D02*
Y-598767D01*
G01Y-599833D02*
X555133Y-599300D01*
X555633Y-598900D01*
X556333Y-598767D01*
X556833Y-598900D01*
X557433Y-599300D01*
G01X562533Y-603167D02*
X563033Y-603700D01*
X563733Y-604100D01*
X564333D01*
X564933Y-603833D01*
X565333Y-603433D01*
X565533Y-602900D01*
X565433Y-602100D01*
X565033Y-601700D01*
X563233Y-600900D01*
X562833Y-599967D01*
X563033Y-599300D01*
X563433Y-598900D01*
X564033Y-598767D01*
X564633Y-598900D01*
X565233Y-599300D01*
G01X572033Y-598767D02*
Y-604100D01*
G01Y-596633D02*
X571833Y-596500D01*
Y-596233D01*
X572033Y-596100D01*
X572233Y-596233D01*
Y-596500D01*
X572033Y-596633D01*
G01X580033Y-604100D02*
X579433Y-603967D01*
X578833Y-603433D01*
X578433Y-602500D01*
X578233Y-601433D01*
X578433Y-600367D01*
X578833Y-599433D01*
X579433Y-598900D01*
X580033Y-598767D01*
X580633Y-598900D01*
X581233Y-599433D01*
X581633Y-600367D01*
X581733Y-601433D01*
X581633Y-602500D01*
X581233Y-603433D01*
X580633Y-603967D01*
X580033Y-604100D01*
G01X586333D02*
Y-598767D01*
G01Y-600100D02*
X586733Y-599433D01*
X587333Y-598900D01*
X588133Y-598767D01*
X588833Y-598900D01*
X589433Y-599433D01*
X589733Y-600367D01*
Y-604100D01*
G01X604033Y-598767D02*
Y-604100D01*
G01Y-596633D02*
X603833Y-596500D01*
Y-596233D01*
X604033Y-596100D01*
X604233Y-596233D01*
Y-596500D01*
X604033Y-596633D01*
G01X610533Y-603167D02*
X611033Y-603700D01*
X611733Y-604100D01*
X612333D01*
X612933Y-603833D01*
X613333Y-603433D01*
X613533Y-602900D01*
X613433Y-602100D01*
X613033Y-601700D01*
X611233Y-600900D01*
X610833Y-599967D01*
X611033Y-599300D01*
X611433Y-598900D01*
X612033Y-598767D01*
X612633Y-598900D01*
X613233Y-599300D01*
G01X618533Y-603167D02*
X619033Y-603700D01*
X619733Y-604100D01*
X620333D01*
X620933Y-603833D01*
X621333Y-603433D01*
X621533Y-602900D01*
X621433Y-602100D01*
X621033Y-601700D01*
X619233Y-600900D01*
X618833Y-599967D01*
X619033Y-599300D01*
X619433Y-598900D01*
X620033Y-598767D01*
X620633Y-598900D01*
X621233Y-599300D01*
G01X626333Y-598767D02*
Y-602500D01*
X626733Y-603433D01*
X627333Y-603967D01*
X628033Y-604100D01*
X628733Y-603967D01*
X629333Y-603433D01*
X629733Y-602500D01*
G01Y-604100D02*
Y-598767D01*
G01X634533Y-600500D02*
X637733D01*
X637433Y-599567D01*
X636933Y-599033D01*
X636233Y-598767D01*
X635533Y-598900D01*
X634933Y-599300D01*
X634533Y-600233D01*
X634333Y-601034D01*
Y-601833D01*
X634533Y-602633D01*
X635033Y-603433D01*
X635633Y-603967D01*
X636333Y-604100D01*
X637033Y-603833D01*
X637733Y-603034D01*
G01X644033Y-604367D02*
X643833Y-604233D01*
Y-603967D01*
X644033Y-603833D01*
X644233Y-603967D01*
Y-604233D01*
X644033Y-604367D01*
G01Y-600767D02*
X643833Y-600633D01*
Y-600367D01*
X644033Y-600233D01*
X644233Y-600367D01*
Y-600633D01*
X644033Y-600767D01*
G01X474033Y-607900D02*
Y-613633D01*
X474433Y-614834D01*
X475233Y-615633D01*
X476233Y-615900D01*
X477233Y-615633D01*
X478033Y-614834D01*
X478433Y-613633D01*
Y-607900D01*
G01X482533Y-615900D02*
Y-610567D01*
G01Y-611900D02*
X482933Y-611233D01*
X483533Y-610700D01*
X484333Y-610567D01*
X485033Y-610700D01*
X485633Y-611233D01*
X485933Y-612167D01*
Y-615900D01*
G01X492233Y-610567D02*
Y-615900D01*
G01Y-608433D02*
X492033Y-608300D01*
Y-608033D01*
X492233Y-607900D01*
X492433Y-608033D01*
Y-608300D01*
X492233Y-608433D01*
G01X500233Y-607900D02*
Y-615900D01*
G01X498833Y-610567D02*
X501633D01*
G01X517833Y-611233D02*
X517133Y-610700D01*
X516533Y-610567D01*
X515733Y-610833D01*
X515133Y-611367D01*
X514733Y-612300D01*
X514633Y-613233D01*
X514733Y-614167D01*
X515133Y-614967D01*
X515733Y-615633D01*
X516533Y-615900D01*
X517233Y-615633D01*
X517833Y-615100D01*
G01X524233Y-615900D02*
X523633Y-615767D01*
X523033Y-615233D01*
X522633Y-614300D01*
X522433Y-613233D01*
X522633Y-612167D01*
X523033Y-611233D01*
X523633Y-610700D01*
X524233Y-610567D01*
X524833Y-610700D01*
X525433Y-611233D01*
X525833Y-612167D01*
X525933Y-613233D01*
X525833Y-614300D01*
X525433Y-615233D01*
X524833Y-615767D01*
X524233Y-615900D01*
G01X530533D02*
Y-610567D01*
G01Y-611900D02*
X530933Y-611233D01*
X531533Y-610700D01*
X532333Y-610567D01*
X533033Y-610700D01*
X533633Y-611233D01*
X533933Y-612167D01*
Y-615900D01*
G01X538433Y-610567D02*
X540233Y-615900D01*
X542033Y-610567D01*
G01X546733Y-612300D02*
X549933D01*
X549633Y-611367D01*
X549133Y-610833D01*
X548433Y-610567D01*
X547733Y-610700D01*
X547133Y-611100D01*
X546733Y-612033D01*
X546533Y-612834D01*
Y-613633D01*
X546733Y-614433D01*
X547233Y-615233D01*
X547833Y-615767D01*
X548533Y-615900D01*
X549233Y-615633D01*
X549933Y-614834D01*
G01X554833Y-615900D02*
Y-610567D01*
G01Y-611633D02*
X555333Y-611100D01*
X555833Y-610700D01*
X556533Y-610567D01*
X557033Y-610700D01*
X557633Y-611100D01*
G01X562733Y-614967D02*
X563233Y-615500D01*
X563933Y-615900D01*
X564533D01*
X565133Y-615633D01*
X565533Y-615233D01*
X565733Y-614700D01*
X565633Y-613900D01*
X565233Y-613500D01*
X563433Y-612700D01*
X563033Y-611767D01*
X563233Y-611100D01*
X563633Y-610700D01*
X564233Y-610567D01*
X564833Y-610700D01*
X565433Y-611100D01*
G01X572233Y-610567D02*
Y-615900D01*
G01Y-608433D02*
X572033Y-608300D01*
Y-608033D01*
X572233Y-607900D01*
X572433Y-608033D01*
Y-608300D01*
X572233Y-608433D01*
G01X580233Y-615900D02*
X579633Y-615767D01*
X579033Y-615233D01*
X578633Y-614300D01*
X578433Y-613233D01*
X578633Y-612167D01*
X579033Y-611233D01*
X579633Y-610700D01*
X580233Y-610567D01*
X580833Y-610700D01*
X581433Y-611233D01*
X581833Y-612167D01*
X581933Y-613233D01*
X581833Y-614300D01*
X581433Y-615233D01*
X580833Y-615767D01*
X580233Y-615900D01*
G01X586533D02*
Y-610567D01*
G01Y-611900D02*
X586933Y-611233D01*
X587533Y-610700D01*
X588333Y-610567D01*
X589033Y-610700D01*
X589633Y-611233D01*
X589933Y-612167D01*
Y-615900D01*
G01X602733Y-612300D02*
X605933D01*
X605633Y-611367D01*
X605133Y-610833D01*
X604433Y-610567D01*
X603733Y-610700D01*
X603133Y-611100D01*
X602733Y-612033D01*
X602533Y-612834D01*
Y-613633D01*
X602733Y-614433D01*
X603233Y-615233D01*
X603833Y-615767D01*
X604533Y-615900D01*
X605233Y-615633D01*
X605933Y-614834D01*
G01X610833Y-615900D02*
Y-610567D01*
G01Y-611633D02*
X611333Y-611100D01*
X611833Y-610700D01*
X612533Y-610567D01*
X613033Y-610700D01*
X613633Y-611100D01*
G01X618833Y-615900D02*
Y-610567D01*
G01Y-611633D02*
X619333Y-611100D01*
X619833Y-610700D01*
X620533Y-610567D01*
X621033Y-610700D01*
X621633Y-611100D01*
G01X628233Y-615900D02*
X627633Y-615767D01*
X627033Y-615233D01*
X626633Y-614300D01*
X626433Y-613233D01*
X626633Y-612167D01*
X627033Y-611233D01*
X627633Y-610700D01*
X628233Y-610567D01*
X628833Y-610700D01*
X629433Y-611233D01*
X629833Y-612167D01*
X629933Y-613233D01*
X629833Y-614300D01*
X629433Y-615233D01*
X628833Y-615767D01*
X628233Y-615900D01*
G01X634833D02*
Y-610567D01*
G01Y-611633D02*
X635333Y-611100D01*
X635833Y-610700D01*
X636533Y-610567D01*
X637033Y-610700D01*
X637633Y-611100D01*
G01X650433Y-615900D02*
Y-607900D01*
G01Y-611900D02*
X650933Y-611100D01*
X651533Y-610700D01*
X652133Y-610567D01*
X653033Y-610833D01*
X653633Y-611367D01*
X654033Y-612300D01*
Y-613367D01*
X653833Y-614433D01*
X653433Y-615233D01*
X652733Y-615767D01*
X652133Y-615900D01*
X651533Y-615767D01*
X650933Y-615367D01*
X650433Y-614700D01*
G01X658733Y-612300D02*
X661933D01*
X661633Y-611367D01*
X661133Y-610833D01*
X660433Y-610567D01*
X659733Y-610700D01*
X659133Y-611100D01*
X658733Y-612033D01*
X658533Y-612834D01*
Y-613633D01*
X658733Y-614433D01*
X659233Y-615233D01*
X659833Y-615767D01*
X660533Y-615900D01*
X661233Y-615633D01*
X661933Y-614834D01*
G01X668233Y-607900D02*
Y-615900D01*
G01X666833Y-610567D02*
X669633D01*
G01X673733D02*
X674933Y-615900D01*
X676233Y-610567D01*
X677533Y-615900D01*
X678733Y-610567D01*
G01X682733Y-612300D02*
X685933D01*
X685633Y-611367D01*
X685133Y-610833D01*
X684433Y-610567D01*
X683733Y-610700D01*
X683133Y-611100D01*
X682733Y-612033D01*
X682533Y-612834D01*
Y-613633D01*
X682733Y-614433D01*
X683233Y-615233D01*
X683833Y-615767D01*
X684533Y-615900D01*
X685233Y-615633D01*
X685933Y-614834D01*
G01X690733Y-612300D02*
X693933D01*
X693633Y-611367D01*
X693133Y-610833D01*
X692433Y-610567D01*
X691733Y-610700D01*
X691133Y-611100D01*
X690733Y-612033D01*
X690533Y-612834D01*
Y-613633D01*
X690733Y-614433D01*
X691233Y-615233D01*
X691833Y-615767D01*
X692533Y-615900D01*
X693233Y-615633D01*
X693933Y-614834D01*
G01X698533Y-615900D02*
Y-610567D01*
G01Y-611900D02*
X698933Y-611233D01*
X699533Y-610700D01*
X700333Y-610567D01*
X701033Y-610700D01*
X701633Y-611233D01*
X701933Y-612167D01*
Y-615900D01*
G01X713233D02*
Y-610567D01*
G01Y-612033D02*
X713533Y-611367D01*
X714033Y-610833D01*
X714733Y-610567D01*
X715433Y-610833D01*
X715933Y-611367D01*
X716233Y-612033D01*
Y-615900D01*
G01Y-612033D02*
X716533Y-611367D01*
X717033Y-610833D01*
X717733Y-610567D01*
X718433Y-610833D01*
X718933Y-611367D01*
X719233Y-612167D01*
Y-615900D01*
G01X722733Y-612300D02*
X725933D01*
X725633Y-611367D01*
X725133Y-610833D01*
X724433Y-610567D01*
X723733Y-610700D01*
X723133Y-611100D01*
X722733Y-612033D01*
X722533Y-612834D01*
Y-613633D01*
X722733Y-614433D01*
X723233Y-615233D01*
X723833Y-615767D01*
X724533Y-615900D01*
X725233Y-615633D01*
X725933Y-614834D01*
G01X732233Y-607900D02*
Y-615900D01*
G01X730833Y-610567D02*
X733633D01*
G01X738833Y-615900D02*
Y-610567D01*
G01Y-611633D02*
X739333Y-611100D01*
X739833Y-610700D01*
X740533Y-610567D01*
X741033Y-610700D01*
X741633Y-611100D01*
G01X748233Y-610567D02*
Y-615900D01*
G01Y-608433D02*
X748033Y-608300D01*
Y-608033D01*
X748233Y-607900D01*
X748433Y-608033D01*
Y-608300D01*
X748233Y-608433D01*
G01X757833Y-611233D02*
X757133Y-610700D01*
X756533Y-610567D01*
X755733Y-610833D01*
X755133Y-611367D01*
X754733Y-612300D01*
X754633Y-613233D01*
X754733Y-614167D01*
X755133Y-614967D01*
X755733Y-615633D01*
X756533Y-615900D01*
X757233Y-615633D01*
X757833Y-615100D01*
G01X774033Y-615900D02*
Y-610567D01*
G01Y-611500D02*
X773633Y-610967D01*
X773033Y-610700D01*
X772333Y-610567D01*
X771633Y-610833D01*
X771033Y-611367D01*
X770633Y-612167D01*
X770433Y-613233D01*
X770633Y-614300D01*
X771033Y-615100D01*
X771633Y-615633D01*
X772333Y-615900D01*
X773033Y-615767D01*
X773633Y-615367D01*
X774033Y-614834D01*
G01X778533Y-615900D02*
Y-610567D01*
G01Y-611900D02*
X778933Y-611233D01*
X779533Y-610700D01*
X780333Y-610567D01*
X781033Y-610700D01*
X781633Y-611233D01*
X781933Y-612167D01*
Y-615900D01*
G01X790033Y-607900D02*
Y-615900D01*
G01Y-614700D02*
X789633Y-615367D01*
X789033Y-615767D01*
X788333Y-615900D01*
X787533Y-615633D01*
X786933Y-614967D01*
X786533Y-614167D01*
X786433Y-613233D01*
X786533Y-612300D01*
X786933Y-611500D01*
X787533Y-610833D01*
X788333Y-610567D01*
X789033Y-610700D01*
X789533Y-610967D01*
X790033Y-611500D01*
G01X806233Y-615900D02*
X802233D01*
Y-607900D01*
X806233D01*
G01X804633Y-611767D02*
X802233D01*
G01X810533Y-615900D02*
Y-610567D01*
G01Y-611900D02*
X810933Y-611233D01*
X811533Y-610700D01*
X812333Y-610567D01*
X813033Y-610700D01*
X813633Y-611233D01*
X813933Y-612167D01*
Y-615900D01*
G01X818833Y-617900D02*
X819533Y-618433D01*
X820333Y-618567D01*
X821033Y-618433D01*
X821633Y-617767D01*
X822033Y-616833D01*
Y-610567D01*
G01Y-611633D02*
X821633Y-611100D01*
X821033Y-610700D01*
X820333Y-610567D01*
X819533Y-610833D01*
X819033Y-611367D01*
X818633Y-612300D01*
X818433Y-613233D01*
X818533Y-614033D01*
X818933Y-614967D01*
X819533Y-615633D01*
X820333Y-615900D01*
X820933Y-615767D01*
X821633Y-615233D01*
X822033Y-614700D01*
G01X828233Y-615900D02*
Y-607900D01*
G01X836233Y-610567D02*
Y-615900D01*
G01Y-608433D02*
X836033Y-608300D01*
Y-608033D01*
X836233Y-607900D01*
X836433Y-608033D01*
Y-608300D01*
X836233Y-608433D01*
G01X842733Y-614967D02*
X843233Y-615500D01*
X843933Y-615900D01*
X844533D01*
X845133Y-615633D01*
X845533Y-615233D01*
X845733Y-614700D01*
X845633Y-613900D01*
X845233Y-613500D01*
X843433Y-612700D01*
X843033Y-611767D01*
X843233Y-611100D01*
X843633Y-610700D01*
X844233Y-610567D01*
X844833Y-610700D01*
X845433Y-611100D01*
G01X850533Y-615900D02*
Y-607900D01*
G01Y-611767D02*
X851033Y-611100D01*
X851533Y-610700D01*
X852333Y-610567D01*
X852933Y-610700D01*
X853633Y-611233D01*
X853933Y-612033D01*
Y-615900D01*
G01X866733Y-614967D02*
X867233Y-615500D01*
X867933Y-615900D01*
X868533D01*
X869133Y-615633D01*
X869533Y-615233D01*
X869733Y-614700D01*
X869633Y-613900D01*
X869233Y-613500D01*
X867433Y-612700D01*
X867033Y-611767D01*
X867233Y-611100D01*
X867633Y-610700D01*
X868233Y-610567D01*
X868833Y-610700D01*
X869433Y-611100D01*
G01X874133Y-618300D02*
X874733Y-618567D01*
X875533Y-618300D01*
X876033Y-617767D01*
X876433Y-617100D01*
X877033Y-614967D01*
X878333Y-610567D01*
G01X875133D02*
X877033Y-614967D01*
G01X882733D02*
X883233Y-615500D01*
X883933Y-615900D01*
X884533D01*
X885133Y-615633D01*
X885533Y-615233D01*
X885733Y-614700D01*
X885633Y-613900D01*
X885233Y-613500D01*
X883433Y-612700D01*
X883033Y-611767D01*
X883233Y-611100D01*
X883633Y-610700D01*
X884233Y-610567D01*
X884833Y-610700D01*
X885433Y-611100D01*
G01X892233Y-607900D02*
Y-615900D01*
G01X890833Y-610567D02*
X893633D01*
G01X898733Y-612300D02*
X901933D01*
X901633Y-611367D01*
X901133Y-610833D01*
X900433Y-610567D01*
X899733Y-610700D01*
X899133Y-611100D01*
X898733Y-612033D01*
X898533Y-612834D01*
Y-613633D01*
X898733Y-614433D01*
X899233Y-615233D01*
X899833Y-615767D01*
X900533Y-615900D01*
X901233Y-615633D01*
X901933Y-614834D01*
G01X905233Y-615900D02*
Y-610567D01*
G01Y-612033D02*
X905533Y-611367D01*
X906033Y-610833D01*
X906733Y-610567D01*
X907433Y-610833D01*
X907933Y-611367D01*
X908233Y-612033D01*
Y-615900D01*
G01Y-612033D02*
X908533Y-611367D01*
X909033Y-610833D01*
X909733Y-610567D01*
X910433Y-610833D01*
X910933Y-611367D01*
X911233Y-612167D01*
Y-615900D01*
G01X924233Y-610567D02*
Y-615900D01*
G01Y-608433D02*
X924033Y-608300D01*
Y-608033D01*
X924233Y-607900D01*
X924433Y-608033D01*
Y-608300D01*
X924233Y-608433D01*
G01X930733Y-614967D02*
X931233Y-615500D01*
X931933Y-615900D01*
X932533D01*
X933133Y-615633D01*
X933533Y-615233D01*
X933733Y-614700D01*
X933633Y-613900D01*
X933233Y-613500D01*
X931433Y-612700D01*
X931033Y-611767D01*
X931233Y-611100D01*
X931633Y-610700D01*
X932233Y-610567D01*
X932833Y-610700D01*
X933433Y-611100D01*
G01X948233Y-615900D02*
Y-607900D01*
G01X954733Y-612300D02*
X957933D01*
X957633Y-611367D01*
X957133Y-610833D01*
X956433Y-610567D01*
X955733Y-610700D01*
X955133Y-611100D01*
X954733Y-612033D01*
X954533Y-612834D01*
Y-613633D01*
X954733Y-614433D01*
X955233Y-615233D01*
X955833Y-615767D01*
X956533Y-615900D01*
X957233Y-615633D01*
X957933Y-614834D01*
G01X962733Y-614967D02*
X963233Y-615500D01*
X963933Y-615900D01*
X964533D01*
X965133Y-615633D01*
X965533Y-615233D01*
X965733Y-614700D01*
X965633Y-613900D01*
X965233Y-613500D01*
X963433Y-612700D01*
X963033Y-611767D01*
X963233Y-611100D01*
X963633Y-610700D01*
X964233Y-610567D01*
X964833Y-610700D01*
X965433Y-611100D01*
G01X970733Y-614967D02*
X971233Y-615500D01*
X971933Y-615900D01*
X972533D01*
X973133Y-615633D01*
X973533Y-615233D01*
X973733Y-614700D01*
X973633Y-613900D01*
X973233Y-613500D01*
X971433Y-612700D01*
X971033Y-611767D01*
X971233Y-611100D01*
X971633Y-610700D01*
X972233Y-610567D01*
X972833Y-610700D01*
X973433Y-611100D01*
G01X988233Y-607900D02*
Y-615900D01*
G01X986833Y-610567D02*
X989633D01*
G01X994533Y-615900D02*
Y-607900D01*
G01Y-611767D02*
X995033Y-611100D01*
X995533Y-610700D01*
X996333Y-610567D01*
X996933Y-610700D01*
X997633Y-611233D01*
X997933Y-612033D01*
Y-615900D01*
G01X1006033D02*
Y-610567D01*
G01Y-611500D02*
X1005633Y-610967D01*
X1005033Y-610700D01*
X1004333Y-610567D01*
X1003633Y-610833D01*
X1003033Y-611367D01*
X1002633Y-612167D01*
X1002433Y-613233D01*
X1002633Y-614300D01*
X1003033Y-615100D01*
X1003633Y-615633D01*
X1004333Y-615900D01*
X1005033Y-615767D01*
X1005633Y-615367D01*
X1006033Y-614834D01*
G01X1010533Y-615900D02*
Y-610567D01*
G01Y-611900D02*
X1010933Y-611233D01*
X1011533Y-610700D01*
X1012333Y-610567D01*
X1013033Y-610700D01*
X1013633Y-611233D01*
X1013933Y-612167D01*
Y-615900D01*
G01X1028233D02*
Y-607900D01*
X1027033Y-609500D01*
G01Y-615900D02*
X1029433D01*
G01X1041233D02*
Y-610567D01*
G01Y-612033D02*
X1041533Y-611367D01*
X1042033Y-610833D01*
X1042733Y-610567D01*
X1043433Y-610833D01*
X1043933Y-611367D01*
X1044233Y-612033D01*
Y-615900D01*
G01Y-612033D02*
X1044533Y-611367D01*
X1045033Y-610833D01*
X1045733Y-610567D01*
X1046433Y-610833D01*
X1046933Y-611367D01*
X1047233Y-612167D01*
Y-615900D01*
G01X1052233Y-610567D02*
Y-615900D01*
G01Y-608433D02*
X1052033Y-608300D01*
Y-608033D01*
X1052233Y-607900D01*
X1052433Y-608033D01*
Y-608300D01*
X1052233Y-608433D01*
G01X1060233Y-615900D02*
Y-607900D01*
G01X1068033Y-617367D02*
X1068433Y-615633D01*
G01X1082433Y-618567D02*
Y-610567D01*
G01Y-611767D02*
X1082933Y-611100D01*
X1083433Y-610700D01*
X1084233Y-610567D01*
X1084933Y-610700D01*
X1085633Y-611367D01*
X1085933Y-612300D01*
X1086033Y-613233D01*
X1085933Y-614167D01*
X1085633Y-615100D01*
X1085033Y-615633D01*
X1084233Y-615900D01*
X1083533Y-615767D01*
X1082833Y-615367D01*
X1082433Y-614834D01*
G01X1092233Y-615900D02*
Y-607900D01*
G01X1098733Y-612300D02*
X1101933D01*
X1101633Y-611367D01*
X1101133Y-610833D01*
X1100433Y-610567D01*
X1099733Y-610700D01*
X1099133Y-611100D01*
X1098733Y-612033D01*
X1098533Y-612834D01*
Y-613633D01*
X1098733Y-614433D01*
X1099233Y-615233D01*
X1099833Y-615767D01*
X1100533Y-615900D01*
X1101233Y-615633D01*
X1101933Y-614834D01*
G01X1110033Y-615900D02*
Y-610567D01*
G01Y-611500D02*
X1109633Y-610967D01*
X1109033Y-610700D01*
X1108333Y-610567D01*
X1107633Y-610833D01*
X1107033Y-611367D01*
X1106633Y-612167D01*
X1106433Y-613233D01*
X1106633Y-614300D01*
X1107033Y-615100D01*
X1107633Y-615633D01*
X1108333Y-615900D01*
X1109033Y-615767D01*
X1109633Y-615367D01*
X1110033Y-614834D01*
G01X1114733Y-614967D02*
X1115233Y-615500D01*
X1115933Y-615900D01*
X1116533D01*
X1117133Y-615633D01*
X1117533Y-615233D01*
X1117733Y-614700D01*
X1117633Y-613900D01*
X1117233Y-613500D01*
X1115433Y-612700D01*
X1115033Y-611767D01*
X1115233Y-611100D01*
X1115633Y-610700D01*
X1116233Y-610567D01*
X1116833Y-610700D01*
X1117433Y-611100D01*
G01X1122733Y-612300D02*
X1125933D01*
X1125633Y-611367D01*
X1125133Y-610833D01*
X1124433Y-610567D01*
X1123733Y-610700D01*
X1123133Y-611100D01*
X1122733Y-612033D01*
X1122533Y-612834D01*
Y-613633D01*
X1122733Y-614433D01*
X1123233Y-615233D01*
X1123833Y-615767D01*
X1124533Y-615900D01*
X1125233Y-615633D01*
X1125933Y-614834D01*
G01X1139633Y-615900D02*
Y-609100D01*
X1139833Y-608433D01*
X1140233Y-608033D01*
X1140833Y-607900D01*
X1141433Y-608167D01*
X1141733Y-608833D01*
G01X1140533Y-611100D02*
X1138533D01*
G01X1148233Y-615900D02*
X1147633Y-615767D01*
X1147033Y-615233D01*
X1146633Y-614300D01*
X1146433Y-613233D01*
X1146633Y-612167D01*
X1147033Y-611233D01*
X1147633Y-610700D01*
X1148233Y-610567D01*
X1148833Y-610700D01*
X1149433Y-611233D01*
X1149833Y-612167D01*
X1149933Y-613233D01*
X1149833Y-614300D01*
X1149433Y-615233D01*
X1148833Y-615767D01*
X1148233Y-615900D01*
G01X1156233D02*
Y-607900D01*
G01X1164233Y-615900D02*
Y-607900D01*
G01X1172233Y-615900D02*
X1171633Y-615767D01*
X1171033Y-615233D01*
X1170633Y-614300D01*
X1170433Y-613233D01*
X1170633Y-612167D01*
X1171033Y-611233D01*
X1171633Y-610700D01*
X1172233Y-610567D01*
X1172833Y-610700D01*
X1173433Y-611233D01*
X1173833Y-612167D01*
X1173933Y-613233D01*
X1173833Y-614300D01*
X1173433Y-615233D01*
X1172833Y-615767D01*
X1172233Y-615900D01*
G01X1177733Y-610567D02*
X1178933Y-615900D01*
X1180233Y-610567D01*
X1181533Y-615900D01*
X1182733Y-610567D01*
G01X1193233Y-615900D02*
Y-610567D01*
G01Y-612033D02*
X1193533Y-611367D01*
X1194033Y-610833D01*
X1194733Y-610567D01*
X1195433Y-610833D01*
X1195933Y-611367D01*
X1196233Y-612033D01*
Y-615900D01*
G01Y-612033D02*
X1196533Y-611367D01*
X1197033Y-610833D01*
X1197733Y-610567D01*
X1198433Y-610833D01*
X1198933Y-611367D01*
X1199233Y-612167D01*
Y-615900D01*
G01X1202733Y-612300D02*
X1205933D01*
X1205633Y-611367D01*
X1205133Y-610833D01*
X1204433Y-610567D01*
X1203733Y-610700D01*
X1203133Y-611100D01*
X1202733Y-612033D01*
X1202533Y-612834D01*
Y-613633D01*
X1202733Y-614433D01*
X1203233Y-615233D01*
X1203833Y-615767D01*
X1204533Y-615900D01*
X1205233Y-615633D01*
X1205933Y-614834D01*
G01X1213833Y-611233D02*
X1213133Y-610700D01*
X1212533Y-610567D01*
X1211733Y-610833D01*
X1211133Y-611367D01*
X1210733Y-612300D01*
X1210633Y-613233D01*
X1210733Y-614167D01*
X1211133Y-614967D01*
X1211733Y-615633D01*
X1212533Y-615900D01*
X1213233Y-615633D01*
X1213833Y-615100D01*
G01X1218533Y-615900D02*
Y-607900D01*
G01Y-611767D02*
X1219033Y-611100D01*
X1219533Y-610700D01*
X1220333Y-610567D01*
X1220933Y-610700D01*
X1221633Y-611233D01*
X1221933Y-612033D01*
Y-615900D01*
G01X1230033D02*
Y-610567D01*
G01Y-611500D02*
X1229633Y-610967D01*
X1229033Y-610700D01*
X1228333Y-610567D01*
X1227633Y-610833D01*
X1227033Y-611367D01*
X1226633Y-612167D01*
X1226433Y-613233D01*
X1226633Y-614300D01*
X1227033Y-615100D01*
X1227633Y-615633D01*
X1228333Y-615900D01*
X1229033Y-615767D01*
X1229633Y-615367D01*
X1230033Y-614834D01*
G01X1234533Y-615900D02*
Y-610567D01*
G01Y-611900D02*
X1234933Y-611233D01*
X1235533Y-610700D01*
X1236333Y-610567D01*
X1237033Y-610700D01*
X1237633Y-611233D01*
X1237933Y-612167D01*
Y-615900D01*
G01X1244233Y-610567D02*
Y-615900D01*
G01Y-608433D02*
X1244033Y-608300D01*
Y-608033D01*
X1244233Y-607900D01*
X1244433Y-608033D01*
Y-608300D01*
X1244233Y-608433D01*
G01X1253833Y-611233D02*
X1253133Y-610700D01*
X1252533Y-610567D01*
X1251733Y-610833D01*
X1251133Y-611367D01*
X1250733Y-612300D01*
X1250633Y-613233D01*
X1250733Y-614167D01*
X1251133Y-614967D01*
X1251733Y-615633D01*
X1252533Y-615900D01*
X1253233Y-615633D01*
X1253833Y-615100D01*
G01X1262033Y-615900D02*
Y-610567D01*
G01Y-611500D02*
X1261633Y-610967D01*
X1261033Y-610700D01*
X1260333Y-610567D01*
X1259633Y-610833D01*
X1259033Y-611367D01*
X1258633Y-612167D01*
X1258433Y-613233D01*
X1258633Y-614300D01*
X1259033Y-615100D01*
X1259633Y-615633D01*
X1260333Y-615900D01*
X1261033Y-615767D01*
X1261633Y-615367D01*
X1262033Y-614834D01*
G01X1268233Y-615900D02*
Y-607900D01*
G01X1286033D02*
Y-615900D01*
G01Y-614700D02*
X1285633Y-615367D01*
X1285033Y-615767D01*
X1284333Y-615900D01*
X1283533Y-615633D01*
X1282933Y-614967D01*
X1282533Y-614167D01*
X1282433Y-613233D01*
X1282533Y-612300D01*
X1282933Y-611500D01*
X1283533Y-610833D01*
X1284333Y-610567D01*
X1285033Y-610700D01*
X1285533Y-610967D01*
X1286033Y-611500D01*
G01X1290833Y-615900D02*
Y-610567D01*
G01Y-611633D02*
X1291333Y-611100D01*
X1291833Y-610700D01*
X1292533Y-610567D01*
X1293033Y-610700D01*
X1293633Y-611100D01*
G01X1302033Y-615900D02*
Y-610567D01*
G01Y-611500D02*
X1301633Y-610967D01*
X1301033Y-610700D01*
X1300333Y-610567D01*
X1299633Y-610833D01*
X1299033Y-611367D01*
X1298633Y-612167D01*
X1298433Y-613233D01*
X1298633Y-614300D01*
X1299033Y-615100D01*
X1299633Y-615633D01*
X1300333Y-615900D01*
X1301033Y-615767D01*
X1301633Y-615367D01*
X1302033Y-614834D01*
G01X1305733Y-610567D02*
X1306933Y-615900D01*
X1308233Y-610567D01*
X1309533Y-615900D01*
X1310733Y-610567D01*
G01X1316233D02*
Y-615900D01*
G01Y-608433D02*
X1316033Y-608300D01*
Y-608033D01*
X1316233Y-607900D01*
X1316433Y-608033D01*
Y-608300D01*
X1316233Y-608433D01*
G01X1322533Y-615900D02*
Y-610567D01*
G01Y-611900D02*
X1322933Y-611233D01*
X1323533Y-610700D01*
X1324333Y-610567D01*
X1325033Y-610700D01*
X1325633Y-611233D01*
X1325933Y-612167D01*
Y-615900D01*
G01X1330833Y-617900D02*
X1331533Y-618433D01*
X1332333Y-618567D01*
X1333033Y-618433D01*
X1333633Y-617767D01*
X1334033Y-616833D01*
Y-610567D01*
G01Y-611633D02*
X1333633Y-611100D01*
X1333033Y-610700D01*
X1332333Y-610567D01*
X1331533Y-610833D01*
X1331033Y-611367D01*
X1330633Y-612300D01*
X1330433Y-613233D01*
X1330533Y-614033D01*
X1330933Y-614967D01*
X1331533Y-615633D01*
X1332333Y-615900D01*
X1332933Y-615767D01*
X1333633Y-615233D01*
X1334033Y-614700D01*
G01X1339533Y-618300D02*
X1340933Y-616433D01*
Y-614567D01*
X1339533D01*
Y-616433D01*
X1340933D01*
G01Y-613233D02*
Y-611367D01*
X1339533D01*
Y-613233D01*
X1340933D01*
G01X531533Y-644600D02*
Y-652600D01*
G01X529233Y-644600D02*
X533833D01*
G01X537833Y-652600D02*
Y-644600D01*
G01Y-648467D02*
X538333Y-647800D01*
X538833Y-647400D01*
X539633Y-647267D01*
X540233Y-647400D01*
X540933Y-647933D01*
X541233Y-648733D01*
Y-652600D01*
G01X546033Y-649000D02*
X549233D01*
X548933Y-648067D01*
X548433Y-647533D01*
X547733Y-647267D01*
X547033Y-647400D01*
X546433Y-647800D01*
X546033Y-648733D01*
X545833Y-649534D01*
Y-650333D01*
X546033Y-651133D01*
X546533Y-651933D01*
X547133Y-652467D01*
X547833Y-652600D01*
X548533Y-652333D01*
X549233Y-651534D01*
G01X553833Y-652600D02*
Y-647267D01*
G01Y-648600D02*
X554233Y-647933D01*
X554833Y-647400D01*
X555633Y-647267D01*
X556333Y-647400D01*
X556933Y-647933D01*
X557233Y-648867D01*
Y-652600D01*
G01X573133Y-647933D02*
X572433Y-647400D01*
X571833Y-647267D01*
X571033Y-647533D01*
X570433Y-648067D01*
X570033Y-649000D01*
X569933Y-649933D01*
X570033Y-650867D01*
X570433Y-651667D01*
X571033Y-652333D01*
X571833Y-652600D01*
X572533Y-652333D01*
X573133Y-651800D01*
G01X579533Y-652600D02*
X578933Y-652467D01*
X578333Y-651933D01*
X577933Y-651000D01*
X577733Y-649933D01*
X577933Y-648867D01*
X578333Y-647933D01*
X578933Y-647400D01*
X579533Y-647267D01*
X580133Y-647400D01*
X580733Y-647933D01*
X581133Y-648867D01*
X581233Y-649933D01*
X581133Y-651000D01*
X580733Y-651933D01*
X580133Y-652467D01*
X579533Y-652600D01*
G01X585833D02*
Y-647267D01*
G01Y-648600D02*
X586233Y-647933D01*
X586833Y-647400D01*
X587633Y-647267D01*
X588333Y-647400D01*
X588933Y-647933D01*
X589233Y-648867D01*
Y-652600D01*
G01X593733Y-647267D02*
X595533Y-652600D01*
X597333Y-647267D01*
G01X602033Y-649000D02*
X605233D01*
X604933Y-648067D01*
X604433Y-647533D01*
X603733Y-647267D01*
X603033Y-647400D01*
X602433Y-647800D01*
X602033Y-648733D01*
X601833Y-649534D01*
Y-650333D01*
X602033Y-651133D01*
X602533Y-651933D01*
X603133Y-652467D01*
X603833Y-652600D01*
X604533Y-652333D01*
X605233Y-651534D01*
G01X610133Y-652600D02*
Y-647267D01*
G01Y-648333D02*
X610633Y-647800D01*
X611133Y-647400D01*
X611833Y-647267D01*
X612333Y-647400D01*
X612933Y-647800D01*
G01X619533Y-644600D02*
Y-652600D01*
G01X618133Y-647267D02*
X620933D01*
G01X633333Y-651000D02*
X633933Y-651933D01*
X634733Y-652467D01*
X635633Y-652600D01*
X636433Y-652467D01*
X637233Y-651800D01*
X637733Y-651000D01*
X637833Y-650200D01*
X637633Y-649267D01*
X636933Y-648600D01*
X636233Y-648333D01*
X635333D01*
G01X636233D02*
X636833Y-647933D01*
X637333Y-647267D01*
X637533Y-646467D01*
X637333Y-645667D01*
X636833Y-645000D01*
X635933Y-644600D01*
X635033Y-644733D01*
X634133Y-645267D01*
G01X643533Y-652867D02*
X643333Y-652733D01*
Y-652467D01*
X643533Y-652333D01*
X643733Y-652467D01*
Y-652733D01*
X643533Y-652867D01*
G01X651533Y-652600D02*
Y-644600D01*
X650333Y-646200D01*
G01Y-652600D02*
X652733D01*
G01X659533D02*
X660233Y-652467D01*
X661033Y-652067D01*
X661533Y-651400D01*
X661733Y-650467D01*
X661533Y-649534D01*
X660933Y-648733D01*
X660033Y-648333D01*
X659033D01*
X658433Y-648067D01*
X657933Y-647400D01*
X657733Y-646467D01*
X658033Y-645533D01*
X658733Y-644867D01*
X659533Y-644600D01*
X660333Y-644867D01*
X661033Y-645533D01*
X661333Y-646467D01*
X661133Y-647400D01*
X660633Y-648067D01*
X660033Y-648333D01*
X659033D01*
X658133Y-648733D01*
X657533Y-649534D01*
X657333Y-650467D01*
X657533Y-651400D01*
X658033Y-652067D01*
X658833Y-652467D01*
X659533Y-652600D01*
G01X664533D02*
Y-647267D01*
G01Y-648733D02*
X664833Y-648067D01*
X665333Y-647533D01*
X666033Y-647267D01*
X666733Y-647533D01*
X667233Y-648067D01*
X667533Y-648733D01*
Y-652600D01*
G01Y-648733D02*
X667833Y-648067D01*
X668333Y-647533D01*
X669033Y-647267D01*
X669733Y-647533D01*
X670233Y-648067D01*
X670533Y-648867D01*
Y-652600D01*
G01X672533D02*
Y-647267D01*
G01Y-648733D02*
X672833Y-648067D01*
X673333Y-647533D01*
X674033Y-647267D01*
X674733Y-647533D01*
X675233Y-648067D01*
X675533Y-648733D01*
Y-652600D01*
G01Y-648733D02*
X675833Y-648067D01*
X676333Y-647533D01*
X677033Y-647267D01*
X677733Y-647533D01*
X678233Y-648067D01*
X678533Y-648867D01*
Y-652600D01*
G01X691533Y-647267D02*
Y-652600D01*
G01Y-645133D02*
X691333Y-645000D01*
Y-644733D01*
X691533Y-644600D01*
X691733Y-644733D01*
Y-645000D01*
X691533Y-645133D01*
G01X697833Y-652600D02*
Y-647267D01*
G01Y-648600D02*
X698233Y-647933D01*
X698833Y-647400D01*
X699633Y-647267D01*
X700333Y-647400D01*
X700933Y-647933D01*
X701233Y-648867D01*
Y-652600D01*
G01X707533Y-644600D02*
Y-652600D01*
G01X706133Y-647267D02*
X708933D01*
G01X715533Y-652600D02*
X714933Y-652467D01*
X714333Y-651933D01*
X713933Y-651000D01*
X713733Y-649933D01*
X713933Y-648867D01*
X714333Y-647933D01*
X714933Y-647400D01*
X715533Y-647267D01*
X716133Y-647400D01*
X716733Y-647933D01*
X717133Y-648867D01*
X717233Y-649933D01*
X717133Y-651000D01*
X716733Y-651933D01*
X716133Y-652467D01*
X715533Y-652600D01*
G01X731533D02*
Y-644600D01*
X730333Y-646200D01*
G01Y-652600D02*
X732733D01*
G01X737633Y-645933D02*
X738233Y-645133D01*
X738933Y-644733D01*
X739733Y-644600D01*
X740733Y-644867D01*
X741433Y-645533D01*
X741633Y-646333D01*
X741533Y-647134D01*
X741133Y-647800D01*
X739133Y-649133D01*
X738233Y-650067D01*
X737633Y-651400D01*
X737433Y-652600D01*
X741633D01*
G01X745333Y-651400D02*
X745933Y-652067D01*
X746633Y-652467D01*
X747533Y-652600D01*
X748433Y-652333D01*
X749133Y-651800D01*
X749633Y-650867D01*
X749733Y-649800D01*
X749533Y-648733D01*
X749033Y-648067D01*
X748333Y-647533D01*
X747633Y-647400D01*
X746933Y-647533D01*
X746033Y-648067D01*
X746333Y-644600D01*
X749033D01*
G01X755533Y-652867D02*
X755333Y-652733D01*
Y-652467D01*
X755533Y-652333D01*
X755733Y-652467D01*
Y-652733D01*
X755533Y-652867D01*
G01X763533Y-652600D02*
Y-644600D01*
X762333Y-646200D01*
G01Y-652600D02*
X764733D01*
G01X769833Y-651667D02*
X770533Y-652333D01*
X771333Y-652600D01*
X772133Y-652333D01*
X772833Y-651534D01*
X773333Y-650333D01*
X773533Y-649133D01*
Y-647667D01*
X773333Y-646467D01*
X772833Y-645400D01*
X772233Y-644867D01*
X771533Y-644600D01*
X770733Y-644867D01*
X770133Y-645400D01*
X769733Y-646200D01*
X769533Y-647267D01*
X769733Y-648200D01*
X770233Y-649133D01*
X770833Y-649667D01*
X771533Y-649800D01*
X772333Y-649534D01*
X772933Y-648867D01*
X773533Y-647667D01*
G01X777633Y-649267D02*
X778333Y-648333D01*
X778933Y-647800D01*
X779733Y-647533D01*
X780433Y-647800D01*
X780933Y-648333D01*
X781333Y-649133D01*
X781433Y-650067D01*
X781333Y-650867D01*
X780933Y-651667D01*
X780333Y-652333D01*
X779633Y-652600D01*
X778833Y-652333D01*
X778133Y-651534D01*
X777733Y-650333D01*
X777633Y-649000D01*
X777833Y-647267D01*
X778133Y-646333D01*
X778633Y-645400D01*
X779333Y-644733D01*
X780033Y-644600D01*
X780733Y-644867D01*
X781233Y-645533D01*
G01X787533Y-652600D02*
X788233Y-652467D01*
X789033Y-652067D01*
X789533Y-651400D01*
X789733Y-650467D01*
X789533Y-649534D01*
X788933Y-648733D01*
X788033Y-648333D01*
X787033D01*
X786433Y-648067D01*
X785933Y-647400D01*
X785733Y-646467D01*
X786033Y-645533D01*
X786733Y-644867D01*
X787533Y-644600D01*
X788333Y-644867D01*
X789033Y-645533D01*
X789333Y-646467D01*
X789133Y-647400D01*
X788633Y-648067D01*
X788033Y-648333D01*
X787033D01*
X786133Y-648733D01*
X785533Y-649534D01*
X785333Y-650467D01*
X785533Y-651400D01*
X786033Y-652067D01*
X786833Y-652467D01*
X787533Y-652600D01*
G01X792533D02*
Y-647267D01*
G01Y-648733D02*
X792833Y-648067D01*
X793333Y-647533D01*
X794033Y-647267D01*
X794733Y-647533D01*
X795233Y-648067D01*
X795533Y-648733D01*
Y-652600D01*
G01Y-648733D02*
X795833Y-648067D01*
X796333Y-647533D01*
X797033Y-647267D01*
X797733Y-647533D01*
X798233Y-648067D01*
X798533Y-648867D01*
Y-652600D01*
G01X803533Y-647267D02*
Y-652600D01*
G01Y-645133D02*
X803333Y-645000D01*
Y-644733D01*
X803533Y-644600D01*
X803733Y-644733D01*
Y-645000D01*
X803533Y-645133D01*
G01X811533Y-652600D02*
Y-644600D01*
G01X819333Y-654067D02*
X819733Y-652333D01*
G01X835533Y-644600D02*
Y-652600D01*
G01X834133Y-647267D02*
X836933D01*
G01X841833Y-652600D02*
Y-644600D01*
G01Y-648467D02*
X842333Y-647800D01*
X842833Y-647400D01*
X843633Y-647267D01*
X844233Y-647400D01*
X844933Y-647933D01*
X845233Y-648733D01*
Y-652600D01*
G01X850033Y-649000D02*
X853233D01*
X852933Y-648067D01*
X852433Y-647533D01*
X851733Y-647267D01*
X851033Y-647400D01*
X850433Y-647800D01*
X850033Y-648733D01*
X849833Y-649534D01*
Y-650333D01*
X850033Y-651133D01*
X850533Y-651933D01*
X851133Y-652467D01*
X851833Y-652600D01*
X852533Y-652333D01*
X853233Y-651534D01*
G01X869333Y-644600D02*
Y-652600D01*
G01Y-651400D02*
X868933Y-652067D01*
X868333Y-652467D01*
X867633Y-652600D01*
X866833Y-652333D01*
X866233Y-651667D01*
X865833Y-650867D01*
X865733Y-649933D01*
X865833Y-649000D01*
X866233Y-648200D01*
X866833Y-647533D01*
X867633Y-647267D01*
X868333Y-647400D01*
X868833Y-647667D01*
X869333Y-648200D01*
G01X875533Y-647267D02*
Y-652600D01*
G01Y-645133D02*
X875333Y-645000D01*
Y-644733D01*
X875533Y-644600D01*
X875733Y-644733D01*
Y-645000D01*
X875533Y-645133D01*
G01X882933Y-652600D02*
Y-645800D01*
X883133Y-645133D01*
X883533Y-644733D01*
X884133Y-644600D01*
X884733Y-644867D01*
X885033Y-645533D01*
G01X883833Y-647800D02*
X881833D01*
G01X890933Y-652600D02*
Y-645800D01*
X891133Y-645133D01*
X891533Y-644733D01*
X892133Y-644600D01*
X892733Y-644867D01*
X893033Y-645533D01*
G01X891833Y-647800D02*
X889833D01*
G01X898033Y-649000D02*
X901233D01*
X900933Y-648067D01*
X900433Y-647533D01*
X899733Y-647267D01*
X899033Y-647400D01*
X898433Y-647800D01*
X898033Y-648733D01*
X897833Y-649534D01*
Y-650333D01*
X898033Y-651133D01*
X898533Y-651933D01*
X899133Y-652467D01*
X899833Y-652600D01*
X900533Y-652333D01*
X901233Y-651534D01*
G01X906133Y-652600D02*
Y-647267D01*
G01Y-648333D02*
X906633Y-647800D01*
X907133Y-647400D01*
X907833Y-647267D01*
X908333Y-647400D01*
X908933Y-647800D01*
G01X914033Y-649000D02*
X917233D01*
X916933Y-648067D01*
X916433Y-647533D01*
X915733Y-647267D01*
X915033Y-647400D01*
X914433Y-647800D01*
X914033Y-648733D01*
X913833Y-649534D01*
Y-650333D01*
X914033Y-651133D01*
X914533Y-651933D01*
X915133Y-652467D01*
X915833Y-652600D01*
X916533Y-652333D01*
X917233Y-651534D01*
G01X921833Y-652600D02*
Y-647267D01*
G01Y-648600D02*
X922233Y-647933D01*
X922833Y-647400D01*
X923633Y-647267D01*
X924333Y-647400D01*
X924933Y-647933D01*
X925233Y-648867D01*
Y-652600D01*
G01X933133Y-647933D02*
X932433Y-647400D01*
X931833Y-647267D01*
X931033Y-647533D01*
X930433Y-648067D01*
X930033Y-649000D01*
X929933Y-649933D01*
X930033Y-650867D01*
X930433Y-651667D01*
X931033Y-652333D01*
X931833Y-652600D01*
X932533Y-652333D01*
X933133Y-651800D01*
G01X938033Y-649000D02*
X941233D01*
X940933Y-648067D01*
X940433Y-647533D01*
X939733Y-647267D01*
X939033Y-647400D01*
X938433Y-647800D01*
X938033Y-648733D01*
X937833Y-649534D01*
Y-650333D01*
X938033Y-651133D01*
X938533Y-651933D01*
X939133Y-652467D01*
X939833Y-652600D01*
X940533Y-652333D01*
X941233Y-651534D01*
G01X953733Y-652600D02*
Y-644600D01*
G01Y-648600D02*
X954233Y-647800D01*
X954833Y-647400D01*
X955433Y-647267D01*
X956333Y-647533D01*
X956933Y-648067D01*
X957333Y-649000D01*
Y-650067D01*
X957133Y-651133D01*
X956733Y-651933D01*
X956033Y-652467D01*
X955433Y-652600D01*
X954833Y-652467D01*
X954233Y-652067D01*
X953733Y-651400D01*
G01X962033Y-649000D02*
X965233D01*
X964933Y-648067D01*
X964433Y-647533D01*
X963733Y-647267D01*
X963033Y-647400D01*
X962433Y-647800D01*
X962033Y-648733D01*
X961833Y-649534D01*
Y-650333D01*
X962033Y-651133D01*
X962533Y-651933D01*
X963133Y-652467D01*
X963833Y-652600D01*
X964533Y-652333D01*
X965233Y-651534D01*
G01X971533Y-644600D02*
Y-652600D01*
G01X970133Y-647267D02*
X972933D01*
G01X977033D02*
X978233Y-652600D01*
X979533Y-647267D01*
X980833Y-652600D01*
X982033Y-647267D01*
G01X986033Y-649000D02*
X989233D01*
X988933Y-648067D01*
X988433Y-647533D01*
X987733Y-647267D01*
X987033Y-647400D01*
X986433Y-647800D01*
X986033Y-648733D01*
X985833Y-649534D01*
Y-650333D01*
X986033Y-651133D01*
X986533Y-651933D01*
X987133Y-652467D01*
X987833Y-652600D01*
X988533Y-652333D01*
X989233Y-651534D01*
G01X994033Y-649000D02*
X997233D01*
X996933Y-648067D01*
X996433Y-647533D01*
X995733Y-647267D01*
X995033Y-647400D01*
X994433Y-647800D01*
X994033Y-648733D01*
X993833Y-649534D01*
Y-650333D01*
X994033Y-651133D01*
X994533Y-651933D01*
X995133Y-652467D01*
X995833Y-652600D01*
X996533Y-652333D01*
X997233Y-651534D01*
G01X1001833Y-652600D02*
Y-647267D01*
G01Y-648600D02*
X1002233Y-647933D01*
X1002833Y-647400D01*
X1003633Y-647267D01*
X1004333Y-647400D01*
X1004933Y-647933D01*
X1005233Y-648867D01*
Y-652600D01*
G01X1019533D02*
Y-644600D01*
X1018333Y-646200D01*
G01Y-652600D02*
X1020733D01*
G01X1025633Y-645933D02*
X1026233Y-645133D01*
X1026933Y-644733D01*
X1027733Y-644600D01*
X1028733Y-644867D01*
X1029433Y-645533D01*
X1029633Y-646333D01*
X1029533Y-647134D01*
X1029133Y-647800D01*
X1027133Y-649133D01*
X1026233Y-650067D01*
X1025633Y-651400D01*
X1025433Y-652600D01*
X1029633D01*
G01X1033633Y-649267D02*
X1034333Y-648333D01*
X1034933Y-647800D01*
X1035733Y-647533D01*
X1036433Y-647800D01*
X1036933Y-648333D01*
X1037333Y-649133D01*
X1037433Y-650067D01*
X1037333Y-650867D01*
X1036933Y-651667D01*
X1036333Y-652333D01*
X1035633Y-652600D01*
X1034833Y-652333D01*
X1034133Y-651534D01*
X1033733Y-650333D01*
X1033633Y-649000D01*
X1033833Y-647267D01*
X1034133Y-646333D01*
X1034633Y-645400D01*
X1035333Y-644733D01*
X1036033Y-644600D01*
X1036733Y-644867D01*
X1037233Y-645533D01*
G01X1040533Y-652600D02*
Y-647267D01*
G01Y-648733D02*
X1040833Y-648067D01*
X1041333Y-647533D01*
X1042033Y-647267D01*
X1042733Y-647533D01*
X1043233Y-648067D01*
X1043533Y-648733D01*
Y-652600D01*
G01Y-648733D02*
X1043833Y-648067D01*
X1044333Y-647533D01*
X1045033Y-647267D01*
X1045733Y-647533D01*
X1046233Y-648067D01*
X1046533Y-648867D01*
Y-652600D01*
G01X1051533Y-647267D02*
Y-652600D01*
G01Y-645133D02*
X1051333Y-645000D01*
Y-644733D01*
X1051533Y-644600D01*
X1051733Y-644733D01*
Y-645000D01*
X1051533Y-645133D01*
G01X1059533Y-652600D02*
Y-644600D01*
G01X1077333Y-652600D02*
Y-647267D01*
G01Y-648200D02*
X1076933Y-647667D01*
X1076333Y-647400D01*
X1075633Y-647267D01*
X1074933Y-647533D01*
X1074333Y-648067D01*
X1073933Y-648867D01*
X1073733Y-649933D01*
X1073933Y-651000D01*
X1074333Y-651800D01*
X1074933Y-652333D01*
X1075633Y-652600D01*
X1076333Y-652467D01*
X1076933Y-652067D01*
X1077333Y-651534D01*
G01X1081833Y-652600D02*
Y-647267D01*
G01Y-648600D02*
X1082233Y-647933D01*
X1082833Y-647400D01*
X1083633Y-647267D01*
X1084333Y-647400D01*
X1084933Y-647933D01*
X1085233Y-648867D01*
Y-652600D01*
G01X1093333Y-644600D02*
Y-652600D01*
G01Y-651400D02*
X1092933Y-652067D01*
X1092333Y-652467D01*
X1091633Y-652600D01*
X1090833Y-652333D01*
X1090233Y-651667D01*
X1089833Y-650867D01*
X1089733Y-649933D01*
X1089833Y-649000D01*
X1090233Y-648200D01*
X1090833Y-647533D01*
X1091633Y-647267D01*
X1092333Y-647400D01*
X1092833Y-647667D01*
X1093333Y-648200D01*
G01X1107533Y-652600D02*
Y-644600D01*
X1106333Y-646200D01*
G01Y-652600D02*
X1108733D01*
G01X1113633Y-645933D02*
X1114233Y-645133D01*
X1114933Y-644733D01*
X1115733Y-644600D01*
X1116733Y-644867D01*
X1117433Y-645533D01*
X1117633Y-646333D01*
X1117533Y-647134D01*
X1117133Y-647800D01*
X1115133Y-649133D01*
X1114233Y-650067D01*
X1113633Y-651400D01*
X1113433Y-652600D01*
X1117633D01*
G01X1121333Y-651400D02*
X1121933Y-652067D01*
X1122633Y-652467D01*
X1123533Y-652600D01*
X1124433Y-652333D01*
X1125133Y-651800D01*
X1125633Y-650867D01*
X1125733Y-649800D01*
X1125533Y-648733D01*
X1125033Y-648067D01*
X1124333Y-647533D01*
X1123633Y-647400D01*
X1122933Y-647533D01*
X1122033Y-648067D01*
X1122333Y-644600D01*
X1125033D01*
G01X1131533Y-652867D02*
X1131333Y-652733D01*
Y-652467D01*
X1131533Y-652333D01*
X1131733Y-652467D01*
Y-652733D01*
X1131533Y-652867D01*
G01X1139533Y-652600D02*
Y-644600D01*
X1138333Y-646200D01*
G01Y-652600D02*
X1140733D01*
G01X1145833Y-651667D02*
X1146533Y-652333D01*
X1147333Y-652600D01*
X1148133Y-652333D01*
X1148833Y-651534D01*
X1149333Y-650333D01*
X1149533Y-649133D01*
Y-647667D01*
X1149333Y-646467D01*
X1148833Y-645400D01*
X1148233Y-644867D01*
X1147533Y-644600D01*
X1146733Y-644867D01*
X1146133Y-645400D01*
X1145733Y-646200D01*
X1145533Y-647267D01*
X1145733Y-648200D01*
X1146233Y-649133D01*
X1146833Y-649667D01*
X1147533Y-649800D01*
X1148333Y-649534D01*
X1148933Y-648867D01*
X1149533Y-647667D01*
G01X1153633Y-649267D02*
X1154333Y-648333D01*
X1154933Y-647800D01*
X1155733Y-647533D01*
X1156433Y-647800D01*
X1156933Y-648333D01*
X1157333Y-649133D01*
X1157433Y-650067D01*
X1157333Y-650867D01*
X1156933Y-651667D01*
X1156333Y-652333D01*
X1155633Y-652600D01*
X1154833Y-652333D01*
X1154133Y-651534D01*
X1153733Y-650333D01*
X1153633Y-649000D01*
X1153833Y-647267D01*
X1154133Y-646333D01*
X1154633Y-645400D01*
X1155333Y-644733D01*
X1156033Y-644600D01*
X1156733Y-644867D01*
X1157233Y-645533D01*
G01X1163533Y-652600D02*
X1164233Y-652467D01*
X1165033Y-652067D01*
X1165533Y-651400D01*
X1165733Y-650467D01*
X1165533Y-649534D01*
X1164933Y-648733D01*
X1164033Y-648333D01*
X1163033D01*
X1162433Y-648067D01*
X1161933Y-647400D01*
X1161733Y-646467D01*
X1162033Y-645533D01*
X1162733Y-644867D01*
X1163533Y-644600D01*
X1164333Y-644867D01*
X1165033Y-645533D01*
X1165333Y-646467D01*
X1165133Y-647400D01*
X1164633Y-648067D01*
X1164033Y-648333D01*
X1163033D01*
X1162133Y-648733D01*
X1161533Y-649534D01*
X1161333Y-650467D01*
X1161533Y-651400D01*
X1162033Y-652067D01*
X1162833Y-652467D01*
X1163533Y-652600D01*
G01X1179533Y-647267D02*
Y-652600D01*
G01Y-645133D02*
X1179333Y-645000D01*
Y-644733D01*
X1179533Y-644600D01*
X1179733Y-644733D01*
Y-645000D01*
X1179533Y-645133D01*
G01X1186033Y-651667D02*
X1186533Y-652200D01*
X1187233Y-652600D01*
X1187833D01*
X1188433Y-652333D01*
X1188833Y-651933D01*
X1189033Y-651400D01*
X1188933Y-650600D01*
X1188533Y-650200D01*
X1186733Y-649400D01*
X1186333Y-648467D01*
X1186533Y-647800D01*
X1186933Y-647400D01*
X1187533Y-647267D01*
X1188133Y-647400D01*
X1188733Y-647800D01*
G01X1203533Y-652600D02*
Y-644600D01*
G01X1210033Y-649000D02*
X1213233D01*
X1212933Y-648067D01*
X1212433Y-647533D01*
X1211733Y-647267D01*
X1211033Y-647400D01*
X1210433Y-647800D01*
X1210033Y-648733D01*
X1209833Y-649534D01*
Y-650333D01*
X1210033Y-651133D01*
X1210533Y-651933D01*
X1211133Y-652467D01*
X1211833Y-652600D01*
X1212533Y-652333D01*
X1213233Y-651534D01*
G01X1218033Y-651667D02*
X1218533Y-652200D01*
X1219233Y-652600D01*
X1219833D01*
X1220433Y-652333D01*
X1220833Y-651933D01*
X1221033Y-651400D01*
X1220933Y-650600D01*
X1220533Y-650200D01*
X1218733Y-649400D01*
X1218333Y-648467D01*
X1218533Y-647800D01*
X1218933Y-647400D01*
X1219533Y-647267D01*
X1220133Y-647400D01*
X1220733Y-647800D01*
G01X1226033Y-651667D02*
X1226533Y-652200D01*
X1227233Y-652600D01*
X1227833D01*
X1228433Y-652333D01*
X1228833Y-651933D01*
X1229033Y-651400D01*
X1228933Y-650600D01*
X1228533Y-650200D01*
X1226733Y-649400D01*
X1226333Y-648467D01*
X1226533Y-647800D01*
X1226933Y-647400D01*
X1227533Y-647267D01*
X1228133Y-647400D01*
X1228733Y-647800D01*
G01X1243533Y-644600D02*
Y-652600D01*
G01X1242133Y-647267D02*
X1244933D01*
G01X1249833Y-652600D02*
Y-644600D01*
G01Y-648467D02*
X1250333Y-647800D01*
X1250833Y-647400D01*
X1251633Y-647267D01*
X1252233Y-647400D01*
X1252933Y-647933D01*
X1253233Y-648733D01*
Y-652600D01*
G01X1261333D02*
Y-647267D01*
G01Y-648200D02*
X1260933Y-647667D01*
X1260333Y-647400D01*
X1259633Y-647267D01*
X1258933Y-647533D01*
X1258333Y-648067D01*
X1257933Y-648867D01*
X1257733Y-649933D01*
X1257933Y-651000D01*
X1258333Y-651800D01*
X1258933Y-652333D01*
X1259633Y-652600D01*
X1260333Y-652467D01*
X1260933Y-652067D01*
X1261333Y-651534D01*
G01X1265833Y-652600D02*
Y-647267D01*
G01Y-648600D02*
X1266233Y-647933D01*
X1266833Y-647400D01*
X1267633Y-647267D01*
X1268333Y-647400D01*
X1268933Y-647933D01*
X1269233Y-648867D01*
Y-652600D01*
G01X1283533D02*
Y-644600D01*
X1282333Y-646200D01*
G01Y-652600D02*
X1284733D01*
G01X1296533D02*
Y-647267D01*
G01Y-648733D02*
X1296833Y-648067D01*
X1297333Y-647533D01*
X1298033Y-647267D01*
X1298733Y-647533D01*
X1299233Y-648067D01*
X1299533Y-648733D01*
Y-652600D01*
G01Y-648733D02*
X1299833Y-648067D01*
X1300333Y-647533D01*
X1301033Y-647267D01*
X1301733Y-647533D01*
X1302233Y-648067D01*
X1302533Y-648867D01*
Y-652600D01*
G01X1307533Y-647267D02*
Y-652600D01*
G01Y-645133D02*
X1307333Y-645000D01*
Y-644733D01*
X1307533Y-644600D01*
X1307733Y-644733D01*
Y-645000D01*
X1307533Y-645133D01*
G01X1315533Y-652600D02*
Y-644600D01*
G01X1323333Y-654067D02*
X1323733Y-652333D01*
G01X531733Y-654600D02*
Y-662600D01*
G01X529433Y-654600D02*
X534033D01*
G01X538033Y-662600D02*
Y-654600D01*
G01Y-658467D02*
X538533Y-657800D01*
X539033Y-657400D01*
X539833Y-657267D01*
X540433Y-657400D01*
X541133Y-657933D01*
X541433Y-658733D01*
Y-662600D01*
G01X546233Y-659000D02*
X549433D01*
X549133Y-658067D01*
X548633Y-657533D01*
X547933Y-657267D01*
X547233Y-657400D01*
X546633Y-657800D01*
X546233Y-658733D01*
X546033Y-659534D01*
Y-660333D01*
X546233Y-661133D01*
X546733Y-661933D01*
X547333Y-662467D01*
X548033Y-662600D01*
X548733Y-662333D01*
X549433Y-661534D01*
G01X554333Y-662600D02*
Y-657267D01*
G01Y-658333D02*
X554833Y-657800D01*
X555333Y-657400D01*
X556033Y-657267D01*
X556533Y-657400D01*
X557133Y-657800D01*
G01X562233Y-659000D02*
X565433D01*
X565133Y-658067D01*
X564633Y-657533D01*
X563933Y-657267D01*
X563233Y-657400D01*
X562633Y-657800D01*
X562233Y-658733D01*
X562033Y-659534D01*
Y-660333D01*
X562233Y-661133D01*
X562733Y-661933D01*
X563333Y-662467D01*
X564033Y-662600D01*
X564733Y-662333D01*
X565433Y-661534D01*
G01X571133Y-662600D02*
Y-655800D01*
X571333Y-655133D01*
X571733Y-654733D01*
X572333Y-654600D01*
X572933Y-654867D01*
X573233Y-655533D01*
G01X572033Y-657800D02*
X570033D01*
G01X579733Y-662600D02*
X579133Y-662467D01*
X578533Y-661933D01*
X578133Y-661000D01*
X577933Y-659933D01*
X578133Y-658867D01*
X578533Y-657933D01*
X579133Y-657400D01*
X579733Y-657267D01*
X580333Y-657400D01*
X580933Y-657933D01*
X581333Y-658867D01*
X581433Y-659933D01*
X581333Y-661000D01*
X580933Y-661933D01*
X580333Y-662467D01*
X579733Y-662600D01*
G01X586333D02*
Y-657267D01*
G01Y-658333D02*
X586833Y-657800D01*
X587333Y-657400D01*
X588033Y-657267D01*
X588533Y-657400D01*
X589133Y-657800D01*
G01X594233Y-659000D02*
X597433D01*
X597133Y-658067D01*
X596633Y-657533D01*
X595933Y-657267D01*
X595233Y-657400D01*
X594633Y-657800D01*
X594233Y-658733D01*
X594033Y-659534D01*
Y-660333D01*
X594233Y-661133D01*
X594733Y-661933D01*
X595333Y-662467D01*
X596033Y-662600D01*
X596733Y-662333D01*
X597433Y-661534D01*
G01X603533Y-664067D02*
X603933Y-662333D01*
G01X617933Y-665267D02*
Y-657267D01*
G01Y-658467D02*
X618433Y-657800D01*
X618933Y-657400D01*
X619733Y-657267D01*
X620433Y-657400D01*
X621133Y-658067D01*
X621433Y-659000D01*
X621533Y-659933D01*
X621433Y-660867D01*
X621133Y-661800D01*
X620533Y-662333D01*
X619733Y-662600D01*
X619033Y-662467D01*
X618333Y-662067D01*
X617933Y-661534D01*
G01X627733Y-662600D02*
Y-654600D01*
G01X634233Y-659000D02*
X637433D01*
X637133Y-658067D01*
X636633Y-657533D01*
X635933Y-657267D01*
X635233Y-657400D01*
X634633Y-657800D01*
X634233Y-658733D01*
X634033Y-659534D01*
Y-660333D01*
X634233Y-661133D01*
X634733Y-661933D01*
X635333Y-662467D01*
X636033Y-662600D01*
X636733Y-662333D01*
X637433Y-661534D01*
G01X645533Y-662600D02*
Y-657267D01*
G01Y-658200D02*
X645133Y-657667D01*
X644533Y-657400D01*
X643833Y-657267D01*
X643133Y-657533D01*
X642533Y-658067D01*
X642133Y-658867D01*
X641933Y-659933D01*
X642133Y-661000D01*
X642533Y-661800D01*
X643133Y-662333D01*
X643833Y-662600D01*
X644533Y-662467D01*
X645133Y-662067D01*
X645533Y-661534D01*
G01X650233Y-661667D02*
X650733Y-662200D01*
X651433Y-662600D01*
X652033D01*
X652633Y-662333D01*
X653033Y-661933D01*
X653233Y-661400D01*
X653133Y-660600D01*
X652733Y-660200D01*
X650933Y-659400D01*
X650533Y-658467D01*
X650733Y-657800D01*
X651133Y-657400D01*
X651733Y-657267D01*
X652333Y-657400D01*
X652933Y-657800D01*
G01X658233Y-659000D02*
X661433D01*
X661133Y-658067D01*
X660633Y-657533D01*
X659933Y-657267D01*
X659233Y-657400D01*
X658633Y-657800D01*
X658233Y-658733D01*
X658033Y-659534D01*
Y-660333D01*
X658233Y-661133D01*
X658733Y-661933D01*
X659333Y-662467D01*
X660033Y-662600D01*
X660733Y-662333D01*
X661433Y-661534D01*
G01X675133Y-662600D02*
Y-655800D01*
X675333Y-655133D01*
X675733Y-654733D01*
X676333Y-654600D01*
X676933Y-654867D01*
X677233Y-655533D01*
G01X676033Y-657800D02*
X674033D01*
G01X683733Y-662600D02*
X683133Y-662467D01*
X682533Y-661933D01*
X682133Y-661000D01*
X681933Y-659933D01*
X682133Y-658867D01*
X682533Y-657933D01*
X683133Y-657400D01*
X683733Y-657267D01*
X684333Y-657400D01*
X684933Y-657933D01*
X685333Y-658867D01*
X685433Y-659933D01*
X685333Y-661000D01*
X684933Y-661933D01*
X684333Y-662467D01*
X683733Y-662600D01*
G01X691733D02*
Y-654600D01*
G01X699733Y-662600D02*
Y-654600D01*
G01X707733Y-662600D02*
X707133Y-662467D01*
X706533Y-661933D01*
X706133Y-661000D01*
X705933Y-659933D01*
X706133Y-658867D01*
X706533Y-657933D01*
X707133Y-657400D01*
X707733Y-657267D01*
X708333Y-657400D01*
X708933Y-657933D01*
X709333Y-658867D01*
X709433Y-659933D01*
X709333Y-661000D01*
X708933Y-661933D01*
X708333Y-662467D01*
X707733Y-662600D01*
G01X713233Y-657267D02*
X714433Y-662600D01*
X715733Y-657267D01*
X717033Y-662600D01*
X718233Y-657267D01*
G01X729533Y-661000D02*
X730133Y-661933D01*
X730933Y-662467D01*
X731833Y-662600D01*
X732633Y-662467D01*
X733433Y-661800D01*
X733933Y-661000D01*
X734033Y-660200D01*
X733833Y-659267D01*
X733133Y-658600D01*
X732433Y-658333D01*
X731533D01*
G01X732433D02*
X733033Y-657933D01*
X733533Y-657267D01*
X733733Y-656467D01*
X733533Y-655667D01*
X733033Y-655000D01*
X732133Y-654600D01*
X731233Y-654733D01*
X730333Y-655267D01*
G01X739733Y-662867D02*
X739533Y-662733D01*
Y-662467D01*
X739733Y-662333D01*
X739933Y-662467D01*
Y-662733D01*
X739733Y-662867D01*
G01X747733Y-662600D02*
Y-654600D01*
X746533Y-656200D01*
G01Y-662600D02*
X748933D01*
G01X755733D02*
X756433Y-662467D01*
X757233Y-662067D01*
X757733Y-661400D01*
X757933Y-660467D01*
X757733Y-659534D01*
X757133Y-658733D01*
X756233Y-658333D01*
X755233D01*
X754633Y-658067D01*
X754133Y-657400D01*
X753933Y-656467D01*
X754233Y-655533D01*
X754933Y-654867D01*
X755733Y-654600D01*
X756533Y-654867D01*
X757233Y-655533D01*
X757533Y-656467D01*
X757333Y-657400D01*
X756833Y-658067D01*
X756233Y-658333D01*
X755233D01*
X754333Y-658733D01*
X753733Y-659534D01*
X753533Y-660467D01*
X753733Y-661400D01*
X754233Y-662067D01*
X755033Y-662467D01*
X755733Y-662600D01*
G01X760733D02*
Y-657267D01*
G01Y-658733D02*
X761033Y-658067D01*
X761533Y-657533D01*
X762233Y-657267D01*
X762933Y-657533D01*
X763433Y-658067D01*
X763733Y-658733D01*
Y-662600D01*
G01Y-658733D02*
X764033Y-658067D01*
X764533Y-657533D01*
X765233Y-657267D01*
X765933Y-657533D01*
X766433Y-658067D01*
X766733Y-658867D01*
Y-662600D01*
G01X768733D02*
Y-657267D01*
G01Y-658733D02*
X769033Y-658067D01*
X769533Y-657533D01*
X770233Y-657267D01*
X770933Y-657533D01*
X771433Y-658067D01*
X771733Y-658733D01*
Y-662600D01*
G01Y-658733D02*
X772033Y-658067D01*
X772533Y-657533D01*
X773233Y-657267D01*
X773933Y-657533D01*
X774433Y-658067D01*
X774733Y-658867D01*
Y-662600D01*
G01X787733Y-654600D02*
Y-662600D01*
G01X786333Y-657267D02*
X789133D01*
G01X795733Y-662600D02*
X795133Y-662467D01*
X794533Y-661933D01*
X794133Y-661000D01*
X793933Y-659933D01*
X794133Y-658867D01*
X794533Y-657933D01*
X795133Y-657400D01*
X795733Y-657267D01*
X796333Y-657400D01*
X796933Y-657933D01*
X797333Y-658867D01*
X797433Y-659933D01*
X797333Y-661000D01*
X796933Y-661933D01*
X796333Y-662467D01*
X795733Y-662600D01*
G01X809933Y-665267D02*
Y-657267D01*
G01Y-658467D02*
X810433Y-657800D01*
X810933Y-657400D01*
X811733Y-657267D01*
X812433Y-657400D01*
X813133Y-658067D01*
X813433Y-659000D01*
X813533Y-659933D01*
X813433Y-660867D01*
X813133Y-661800D01*
X812533Y-662333D01*
X811733Y-662600D01*
X811033Y-662467D01*
X810333Y-662067D01*
X809933Y-661534D01*
G01X818333Y-662600D02*
Y-657267D01*
G01Y-658333D02*
X818833Y-657800D01*
X819333Y-657400D01*
X820033Y-657267D01*
X820533Y-657400D01*
X821133Y-657800D01*
G01X827733Y-662600D02*
X827133Y-662467D01*
X826533Y-661933D01*
X826133Y-661000D01*
X825933Y-659933D01*
X826133Y-658867D01*
X826533Y-657933D01*
X827133Y-657400D01*
X827733Y-657267D01*
X828333Y-657400D01*
X828933Y-657933D01*
X829333Y-658867D01*
X829433Y-659933D01*
X829333Y-661000D01*
X828933Y-661933D01*
X828333Y-662467D01*
X827733Y-662600D01*
G01X837533Y-654600D02*
Y-662600D01*
G01Y-661400D02*
X837133Y-662067D01*
X836533Y-662467D01*
X835833Y-662600D01*
X835033Y-662333D01*
X834433Y-661667D01*
X834033Y-660867D01*
X833933Y-659933D01*
X834033Y-659000D01*
X834433Y-658200D01*
X835033Y-657533D01*
X835833Y-657267D01*
X836533Y-657400D01*
X837033Y-657667D01*
X837533Y-658200D01*
G01X842033Y-657267D02*
Y-661000D01*
X842433Y-661933D01*
X843033Y-662467D01*
X843733Y-662600D01*
X844433Y-662467D01*
X845033Y-661933D01*
X845433Y-661000D01*
G01Y-662600D02*
Y-657267D01*
G01X853333Y-657933D02*
X852633Y-657400D01*
X852033Y-657267D01*
X851233Y-657533D01*
X850633Y-658067D01*
X850233Y-659000D01*
X850133Y-659933D01*
X850233Y-660867D01*
X850633Y-661667D01*
X851233Y-662333D01*
X852033Y-662600D01*
X852733Y-662333D01*
X853333Y-661800D01*
G01X858233Y-659000D02*
X861433D01*
X861133Y-658067D01*
X860633Y-657533D01*
X859933Y-657267D01*
X859233Y-657400D01*
X858633Y-657800D01*
X858233Y-658733D01*
X858033Y-659534D01*
Y-660333D01*
X858233Y-661133D01*
X858733Y-661933D01*
X859333Y-662467D01*
X860033Y-662600D01*
X860733Y-662333D01*
X861433Y-661534D01*
G01X875733Y-654600D02*
Y-662600D01*
G01X874333Y-657267D02*
X877133D01*
G01X882033Y-662600D02*
Y-654600D01*
G01Y-658467D02*
X882533Y-657800D01*
X883033Y-657400D01*
X883833Y-657267D01*
X884433Y-657400D01*
X885133Y-657933D01*
X885433Y-658733D01*
Y-662600D01*
G01X891733Y-657267D02*
Y-662600D01*
G01Y-655133D02*
X891533Y-655000D01*
Y-654733D01*
X891733Y-654600D01*
X891933Y-654733D01*
Y-655000D01*
X891733Y-655133D01*
G01X898233Y-661667D02*
X898733Y-662200D01*
X899433Y-662600D01*
X900033D01*
X900633Y-662333D01*
X901033Y-661933D01*
X901233Y-661400D01*
X901133Y-660600D01*
X900733Y-660200D01*
X898933Y-659400D01*
X898533Y-658467D01*
X898733Y-657800D01*
X899133Y-657400D01*
X899733Y-657267D01*
X900333Y-657400D01*
X900933Y-657800D01*
G01X913933Y-662600D02*
Y-654600D01*
G01Y-658600D02*
X914433Y-657800D01*
X915033Y-657400D01*
X915633Y-657267D01*
X916533Y-657533D01*
X917133Y-658067D01*
X917533Y-659000D01*
Y-660067D01*
X917333Y-661133D01*
X916933Y-661933D01*
X916233Y-662467D01*
X915633Y-662600D01*
X915033Y-662467D01*
X914433Y-662067D01*
X913933Y-661400D01*
G01X923733Y-662600D02*
X923133Y-662467D01*
X922533Y-661933D01*
X922133Y-661000D01*
X921933Y-659933D01*
X922133Y-658867D01*
X922533Y-657933D01*
X923133Y-657400D01*
X923733Y-657267D01*
X924333Y-657400D01*
X924933Y-657933D01*
X925333Y-658867D01*
X925433Y-659933D01*
X925333Y-661000D01*
X924933Y-661933D01*
X924333Y-662467D01*
X923733Y-662600D01*
G01X933533D02*
Y-657267D01*
G01Y-658200D02*
X933133Y-657667D01*
X932533Y-657400D01*
X931833Y-657267D01*
X931133Y-657533D01*
X930533Y-658067D01*
X930133Y-658867D01*
X929933Y-659933D01*
X930133Y-661000D01*
X930533Y-661800D01*
X931133Y-662333D01*
X931833Y-662600D01*
X932533Y-662467D01*
X933133Y-662067D01*
X933533Y-661534D01*
G01X938333Y-662600D02*
Y-657267D01*
G01Y-658333D02*
X938833Y-657800D01*
X939333Y-657400D01*
X940033Y-657267D01*
X940533Y-657400D01*
X941133Y-657800D01*
G01X949533Y-654600D02*
Y-662600D01*
G01Y-661400D02*
X949133Y-662067D01*
X948533Y-662467D01*
X947833Y-662600D01*
X947033Y-662333D01*
X946433Y-661667D01*
X946033Y-660867D01*
X945933Y-659933D01*
X946033Y-659000D01*
X946433Y-658200D01*
X947033Y-657533D01*
X947833Y-657267D01*
X948533Y-657400D01*
X949033Y-657667D01*
X949533Y-658200D01*
G01X955733Y-662867D02*
X955533Y-662733D01*
Y-662467D01*
X955733Y-662333D01*
X955933Y-662467D01*
Y-662733D01*
X955733Y-662867D01*
G01X515333Y-508500D02*
Y-500500D01*
X514133Y-502100D01*
G01Y-508500D02*
X516533D01*
G01X523333Y-500500D02*
X522533Y-500767D01*
X521933Y-501433D01*
X521533Y-502233D01*
X521233Y-503300D01*
X521133Y-504500D01*
X521233Y-505700D01*
X521533Y-506767D01*
X521933Y-507567D01*
X522533Y-508233D01*
X523333Y-508500D01*
X524133Y-508233D01*
X524733Y-507567D01*
X525133Y-506767D01*
X525433Y-505700D01*
X525533Y-504500D01*
X525433Y-503300D01*
X525133Y-502233D01*
X524733Y-501433D01*
X524133Y-500767D01*
X523333Y-500500D01*
G01X515960Y-521500D02*
Y-513500D01*
X514760Y-515100D01*
G01Y-521500D02*
X517160D01*
G01X523960D02*
Y-513500D01*
X522760Y-515100D01*
G01Y-521500D02*
X525160D01*
G01X515934Y-534000D02*
Y-526000D01*
X514734Y-527600D01*
G01Y-534000D02*
X517134D01*
G01X522034Y-527333D02*
X522634Y-526533D01*
X523334Y-526133D01*
X524134Y-526000D01*
X525134Y-526267D01*
X525834Y-526933D01*
X526034Y-527733D01*
X525934Y-528534D01*
X525534Y-529200D01*
X523534Y-530533D01*
X522634Y-531467D01*
X522034Y-532800D01*
X521834Y-534000D01*
X526034D01*
G01X513933Y-455495D02*
X514633Y-454561D01*
X515233Y-454028D01*
X516033Y-453761D01*
X516733Y-454028D01*
X517233Y-454561D01*
X517633Y-455361D01*
X517733Y-456295D01*
X517633Y-457095D01*
X517233Y-457895D01*
X516633Y-458561D01*
X515933Y-458828D01*
X515133Y-458561D01*
X514433Y-457762D01*
X514033Y-456561D01*
X513933Y-455228D01*
X514133Y-453495D01*
X514433Y-452561D01*
X514933Y-451628D01*
X515633Y-450961D01*
X516333Y-450828D01*
X517033Y-451095D01*
X517533Y-451761D01*
G01X513633Y-444300D02*
X514233Y-444967D01*
X514933Y-445367D01*
X515833Y-445500D01*
X516733Y-445233D01*
X517433Y-444700D01*
X517933Y-443767D01*
X518033Y-442700D01*
X517833Y-441633D01*
X517333Y-440967D01*
X516633Y-440433D01*
X515933Y-440300D01*
X515233Y-440433D01*
X514333Y-440967D01*
X514633Y-437500D01*
X517333D01*
G01X515633Y-471000D02*
X515833Y-469267D01*
X516133Y-467800D01*
X516533Y-466467D01*
X517033Y-465000D01*
X517833Y-463000D01*
X513833D01*
G01X513633Y-495067D02*
X514333Y-495733D01*
X515133Y-496000D01*
X515933Y-495733D01*
X516633Y-494934D01*
X517133Y-493733D01*
X517333Y-492533D01*
Y-491067D01*
X517133Y-489867D01*
X516633Y-488800D01*
X516033Y-488267D01*
X515333Y-488000D01*
X514533Y-488267D01*
X513933Y-488800D01*
X513533Y-489600D01*
X513333Y-490667D01*
X513533Y-491600D01*
X514033Y-492533D01*
X514633Y-493067D01*
X515333Y-493200D01*
X516133Y-492934D01*
X516733Y-492267D01*
X517333Y-491067D01*
G01X515333Y-484000D02*
X516033Y-483867D01*
X516833Y-483467D01*
X517333Y-482800D01*
X517533Y-481867D01*
X517333Y-480934D01*
X516733Y-480133D01*
X515833Y-479733D01*
X514833D01*
X514233Y-479467D01*
X513733Y-478800D01*
X513533Y-477867D01*
X513833Y-476933D01*
X514533Y-476267D01*
X515333Y-476000D01*
X516133Y-476267D01*
X516833Y-476933D01*
X517133Y-477867D01*
X516933Y-478800D01*
X516433Y-479467D01*
X515833Y-479733D01*
X514833D01*
X513933Y-480133D01*
X513333Y-480934D01*
X513133Y-481867D01*
X513333Y-482800D01*
X513833Y-483467D01*
X514633Y-483867D01*
X515333Y-484000D01*
G01X514133Y-419400D02*
X514733Y-420333D01*
X515533Y-420867D01*
X516433Y-421000D01*
X517233Y-420867D01*
X518033Y-420200D01*
X518533Y-419400D01*
X518633Y-418600D01*
X518433Y-417667D01*
X517733Y-417000D01*
X517033Y-416733D01*
X516133D01*
G01X517033D02*
X517633Y-416333D01*
X518133Y-415667D01*
X518333Y-414867D01*
X518133Y-414067D01*
X517633Y-413400D01*
X516733Y-413000D01*
X515833Y-413133D01*
X514933Y-413667D01*
G01X516333Y-396000D02*
Y-388000D01*
X515133Y-389600D01*
G01Y-396000D02*
X517533D01*
G01X514433Y-401833D02*
X515033Y-401033D01*
X515733Y-400633D01*
X516533Y-400500D01*
X517533Y-400767D01*
X518233Y-401433D01*
X518433Y-402233D01*
X518333Y-403034D01*
X517933Y-403700D01*
X515933Y-405033D01*
X515033Y-405967D01*
X514433Y-407300D01*
X514233Y-408500D01*
X518433D01*
G01X517033Y-434000D02*
Y-426000D01*
X513333Y-431733D01*
X518333D01*
G01X506533Y-380500D02*
Y-372500D01*
X511133Y-380500D01*
Y-372500D01*
G01X516833Y-380500D02*
X516033Y-380367D01*
X515333Y-379833D01*
X514733Y-379033D01*
X514333Y-378100D01*
X514133Y-377033D01*
Y-375967D01*
X514333Y-374900D01*
X514733Y-373967D01*
X515333Y-373167D01*
X516033Y-372633D01*
X516833Y-372500D01*
X517633Y-372633D01*
X518333Y-373167D01*
X518933Y-373967D01*
X519333Y-374900D01*
X519533Y-375967D01*
Y-377033D01*
X519333Y-378100D01*
X518933Y-379033D01*
X518333Y-379833D01*
X517633Y-380367D01*
X516833Y-380500D01*
G01X524833Y-380767D02*
X524633Y-380633D01*
Y-380367D01*
X524833Y-380233D01*
X525033Y-380367D01*
Y-380633D01*
X524833Y-380767D01*
G01X548333Y-533500D02*
Y-525500D01*
X550833D01*
X551633Y-525900D01*
X552133Y-526433D01*
X552333Y-527500D01*
X552133Y-528567D01*
X551533Y-529233D01*
X550833Y-529633D01*
X548333D01*
G01X550833D02*
X552333Y-533500D01*
G01X558333D02*
X557733Y-533367D01*
X557133Y-532833D01*
X556733Y-531900D01*
X556533Y-530833D01*
X556733Y-529767D01*
X557133Y-528833D01*
X557733Y-528300D01*
X558333Y-528167D01*
X558933Y-528300D01*
X559533Y-528833D01*
X559933Y-529767D01*
X560033Y-530833D01*
X559933Y-531900D01*
X559533Y-532833D01*
X558933Y-533367D01*
X558333Y-533500D01*
G01X564633Y-528167D02*
Y-531900D01*
X565033Y-532833D01*
X565633Y-533367D01*
X566333Y-533500D01*
X567033Y-533367D01*
X567633Y-532833D01*
X568033Y-531900D01*
G01Y-533500D02*
Y-528167D01*
G01X572933Y-535500D02*
X573633Y-536033D01*
X574433Y-536167D01*
X575133Y-536033D01*
X575733Y-535367D01*
X576133Y-534433D01*
Y-528167D01*
G01Y-529233D02*
X575733Y-528700D01*
X575133Y-528300D01*
X574433Y-528167D01*
X573633Y-528433D01*
X573133Y-528967D01*
X572733Y-529900D01*
X572533Y-530833D01*
X572633Y-531633D01*
X573033Y-532567D01*
X573633Y-533233D01*
X574433Y-533500D01*
X575033Y-533367D01*
X575733Y-532833D01*
X576133Y-532300D01*
G01X580633Y-533500D02*
Y-525500D01*
G01Y-529367D02*
X581133Y-528700D01*
X581633Y-528300D01*
X582433Y-528167D01*
X583033Y-528300D01*
X583733Y-528833D01*
X584033Y-529633D01*
Y-533500D01*
G01X588633D02*
Y-528167D01*
G01Y-529500D02*
X589033Y-528833D01*
X589633Y-528300D01*
X590433Y-528167D01*
X591133Y-528300D01*
X591733Y-528833D01*
X592033Y-529767D01*
Y-533500D01*
G01X596833Y-529900D02*
X600033D01*
X599733Y-528967D01*
X599233Y-528433D01*
X598533Y-528167D01*
X597833Y-528300D01*
X597233Y-528700D01*
X596833Y-529633D01*
X596633Y-530434D01*
Y-531233D01*
X596833Y-532033D01*
X597333Y-532833D01*
X597933Y-533367D01*
X598633Y-533500D01*
X599333Y-533233D01*
X600033Y-532434D01*
G01X604833Y-532567D02*
X605333Y-533100D01*
X606033Y-533500D01*
X606633D01*
X607233Y-533233D01*
X607633Y-532833D01*
X607833Y-532300D01*
X607733Y-531500D01*
X607333Y-531100D01*
X605533Y-530300D01*
X605133Y-529367D01*
X605333Y-528700D01*
X605733Y-528300D01*
X606333Y-528167D01*
X606933Y-528300D01*
X607533Y-528700D01*
G01X612833Y-532567D02*
X613333Y-533100D01*
X614033Y-533500D01*
X614633D01*
X615233Y-533233D01*
X615633Y-532833D01*
X615833Y-532300D01*
X615733Y-531500D01*
X615333Y-531100D01*
X613533Y-530300D01*
X613133Y-529367D01*
X613333Y-528700D01*
X613733Y-528300D01*
X614333Y-528167D01*
X614933Y-528300D01*
X615533Y-528700D01*
G01X587733Y-465434D02*
X588533Y-466100D01*
X589433Y-466500D01*
X590233D01*
X591033Y-466100D01*
X591633Y-465434D01*
X591933Y-464500D01*
X591733Y-463567D01*
X591233Y-462767D01*
X590333Y-462233D01*
X589133Y-461967D01*
X588433Y-461433D01*
X588133Y-460500D01*
X588333Y-459567D01*
X588833Y-458900D01*
X589533Y-458500D01*
X590233D01*
X590933Y-458767D01*
X591533Y-459433D01*
G01X597833Y-461167D02*
Y-466500D01*
G01Y-459033D02*
X597633Y-458900D01*
Y-458633D01*
X597833Y-458500D01*
X598033Y-458633D01*
Y-458900D01*
X597833Y-459033D01*
G01X604333Y-461167D02*
X607333D01*
X604333Y-466500D01*
X607333D01*
G01X612333Y-462900D02*
X615533D01*
X615233Y-461967D01*
X614733Y-461433D01*
X614033Y-461167D01*
X613333Y-461300D01*
X612733Y-461700D01*
X612333Y-462633D01*
X612133Y-463434D01*
Y-464233D01*
X612333Y-465033D01*
X612833Y-465833D01*
X613433Y-466367D01*
X614133Y-466500D01*
X614833Y-466233D01*
X615533Y-465434D01*
G01X544733Y-466500D02*
Y-458500D01*
G01X548933D02*
Y-466500D01*
G01Y-462500D02*
X544733D01*
G01X554833Y-466500D02*
X554233Y-466367D01*
X553633Y-465833D01*
X553233Y-464900D01*
X553033Y-463833D01*
X553233Y-462767D01*
X553633Y-461833D01*
X554233Y-461300D01*
X554833Y-461167D01*
X555433Y-461300D01*
X556033Y-461833D01*
X556433Y-462767D01*
X556533Y-463833D01*
X556433Y-464900D01*
X556033Y-465833D01*
X555433Y-466367D01*
X554833Y-466500D01*
G01X562833D02*
Y-458500D01*
G01X569333Y-462900D02*
X572533D01*
X572233Y-461967D01*
X571733Y-461433D01*
X571033Y-461167D01*
X570333Y-461300D01*
X569733Y-461700D01*
X569333Y-462633D01*
X569133Y-463434D01*
Y-464233D01*
X569333Y-465033D01*
X569833Y-465833D01*
X570433Y-466367D01*
X571133Y-466500D01*
X571833Y-466233D01*
X572533Y-465434D01*
G01X575062Y-397000D02*
X577562Y-389000D01*
X580062Y-397000D01*
G01X579162Y-394200D02*
X575962D01*
G01X585562Y-397000D02*
Y-389000D01*
G01X593562Y-391667D02*
Y-397000D01*
G01Y-389533D02*
X593362Y-389400D01*
Y-389133D01*
X593562Y-389000D01*
X593762Y-389133D01*
Y-389400D01*
X593562Y-389533D01*
G01X600162Y-399000D02*
X600862Y-399533D01*
X601662Y-399667D01*
X602362Y-399533D01*
X602962Y-398867D01*
X603362Y-397933D01*
Y-391667D01*
G01Y-392733D02*
X602962Y-392200D01*
X602362Y-391800D01*
X601662Y-391667D01*
X600862Y-391933D01*
X600362Y-392467D01*
X599962Y-393400D01*
X599762Y-394333D01*
X599862Y-395133D01*
X600262Y-396067D01*
X600862Y-396733D01*
X601662Y-397000D01*
X602262Y-396867D01*
X602962Y-396333D01*
X603362Y-395800D01*
G01X607862Y-397000D02*
Y-391667D01*
G01Y-393000D02*
X608262Y-392333D01*
X608862Y-391800D01*
X609662Y-391667D01*
X610362Y-391800D01*
X610962Y-392333D01*
X611262Y-393267D01*
Y-397000D01*
G01X614562D02*
Y-391667D01*
G01Y-393133D02*
X614862Y-392467D01*
X615362Y-391933D01*
X616062Y-391667D01*
X616762Y-391933D01*
X617262Y-392467D01*
X617562Y-393133D01*
Y-397000D01*
G01Y-393133D02*
X617862Y-392467D01*
X618362Y-391933D01*
X619062Y-391667D01*
X619762Y-391933D01*
X620262Y-392467D01*
X620562Y-393267D01*
Y-397000D01*
G01X624062Y-393400D02*
X627262D01*
X626962Y-392467D01*
X626462Y-391933D01*
X625762Y-391667D01*
X625062Y-391800D01*
X624462Y-392200D01*
X624062Y-393133D01*
X623862Y-393934D01*
Y-394733D01*
X624062Y-395533D01*
X624562Y-396333D01*
X625162Y-396867D01*
X625862Y-397000D01*
X626562Y-396733D01*
X627262Y-395934D01*
G01X631862Y-397000D02*
Y-391667D01*
G01Y-393000D02*
X632262Y-392333D01*
X632862Y-391800D01*
X633662Y-391667D01*
X634362Y-391800D01*
X634962Y-392333D01*
X635262Y-393267D01*
Y-397000D01*
G01X641562Y-389000D02*
Y-397000D01*
G01X640162Y-391667D02*
X642962D01*
G01X540462Y-396500D02*
Y-388500D01*
G01X544662D02*
Y-396500D01*
G01Y-392500D02*
X540462D01*
G01X550562Y-396500D02*
X549962Y-396367D01*
X549362Y-395833D01*
X548962Y-394900D01*
X548762Y-393833D01*
X548962Y-392767D01*
X549362Y-391833D01*
X549962Y-391300D01*
X550562Y-391167D01*
X551162Y-391300D01*
X551762Y-391833D01*
X552162Y-392767D01*
X552262Y-393833D01*
X552162Y-394900D01*
X551762Y-395833D01*
X551162Y-396367D01*
X550562Y-396500D01*
G01X558562D02*
Y-388500D01*
G01X565062Y-392900D02*
X568262D01*
X567962Y-391967D01*
X567462Y-391433D01*
X566762Y-391167D01*
X566062Y-391300D01*
X565462Y-391700D01*
X565062Y-392633D01*
X564862Y-393434D01*
Y-394233D01*
X565062Y-395033D01*
X565562Y-395833D01*
X566162Y-396367D01*
X566862Y-396500D01*
X567562Y-396233D01*
X568262Y-395434D01*
G01X649333Y-509500D02*
Y-501500D01*
X651733D01*
X652533Y-501900D01*
X653133Y-502833D01*
X653333Y-503900D01*
X653133Y-504967D01*
X652633Y-505767D01*
X651733Y-506167D01*
X649333D01*
G01X659333Y-501500D02*
Y-509500D01*
G01X657033Y-501500D02*
X661633D01*
G01X665233Y-509500D02*
Y-501500D01*
G01X669433D02*
Y-509500D01*
G01Y-505500D02*
X665233D01*
G01X673533Y-509767D02*
X677133Y-501500D01*
G01X681033Y-509500D02*
Y-501500D01*
X685633Y-509500D01*
Y-501500D01*
G01X689333Y-509500D02*
Y-501500D01*
X691733D01*
X692533Y-501900D01*
X693133Y-502833D01*
X693333Y-503900D01*
X693133Y-504967D01*
X692633Y-505767D01*
X691733Y-506167D01*
X689333D01*
G01X699333Y-501500D02*
Y-509500D01*
G01X697033Y-501500D02*
X701633D01*
G01X705233Y-509500D02*
Y-501500D01*
G01X709433D02*
Y-509500D01*
G01Y-505500D02*
X705233D01*
G01X721333Y-509500D02*
X725333Y-506833D01*
X721333Y-504167D01*
G01X730033Y-508033D02*
X732633D01*
G01Y-505633D02*
X730033D01*
G01X737133Y-508300D02*
X737733Y-508967D01*
X738433Y-509367D01*
X739333Y-509500D01*
X740233Y-509233D01*
X740933Y-508700D01*
X741433Y-507767D01*
X741533Y-506700D01*
X741333Y-505633D01*
X740833Y-504967D01*
X740133Y-504433D01*
X739433Y-504300D01*
X738733Y-504433D01*
X737833Y-504967D01*
X738133Y-501500D01*
X740833D01*
G01X752333Y-509500D02*
Y-504167D01*
G01Y-505633D02*
X752633Y-504967D01*
X753133Y-504433D01*
X753833Y-504167D01*
X754533Y-504433D01*
X755033Y-504967D01*
X755333Y-505633D01*
Y-509500D01*
G01Y-505633D02*
X755633Y-504967D01*
X756133Y-504433D01*
X756833Y-504167D01*
X757533Y-504433D01*
X758033Y-504967D01*
X758333Y-505767D01*
Y-509500D01*
G01X760333D02*
Y-504167D01*
G01Y-505633D02*
X760633Y-504967D01*
X761133Y-504433D01*
X761833Y-504167D01*
X762533Y-504433D01*
X763033Y-504967D01*
X763333Y-505633D01*
Y-509500D01*
G01Y-505633D02*
X763633Y-504967D01*
X764133Y-504433D01*
X764833Y-504167D01*
X765533Y-504433D01*
X766033Y-504967D01*
X766333Y-505767D01*
Y-509500D01*
G01X651333Y-521000D02*
X650533Y-520867D01*
X649833Y-520333D01*
X649233Y-519533D01*
X648833Y-518600D01*
X648633Y-517533D01*
Y-516467D01*
X648833Y-515400D01*
X649233Y-514467D01*
X649833Y-513667D01*
X650533Y-513133D01*
X651333Y-513000D01*
X652133Y-513133D01*
X652833Y-513667D01*
X653433Y-514467D01*
X653833Y-515400D01*
X654033Y-516467D01*
Y-517533D01*
X653833Y-518600D01*
X653433Y-519533D01*
X652833Y-520333D01*
X652133Y-520867D01*
X651333Y-521000D01*
G01X659333Y-513000D02*
Y-521000D01*
G01X657933Y-515667D02*
X660733D01*
G01X665633Y-521000D02*
Y-513000D01*
G01Y-516867D02*
X666133Y-516200D01*
X666633Y-515800D01*
X667433Y-515667D01*
X668033Y-515800D01*
X668733Y-516333D01*
X669033Y-517133D01*
Y-521000D01*
G01X673833Y-517400D02*
X677033D01*
X676733Y-516467D01*
X676233Y-515933D01*
X675533Y-515667D01*
X674833Y-515800D01*
X674233Y-516200D01*
X673833Y-517133D01*
X673633Y-517934D01*
Y-518733D01*
X673833Y-519533D01*
X674333Y-520333D01*
X674933Y-520867D01*
X675633Y-521000D01*
X676333Y-520733D01*
X677033Y-519934D01*
G01X681933Y-521000D02*
Y-515667D01*
G01Y-516733D02*
X682433Y-516200D01*
X682933Y-515800D01*
X683633Y-515667D01*
X684133Y-515800D01*
X684733Y-516200D01*
G01X689833Y-520067D02*
X690333Y-520600D01*
X691033Y-521000D01*
X691633D01*
X692233Y-520733D01*
X692633Y-520333D01*
X692833Y-519800D01*
X692733Y-519000D01*
X692333Y-518600D01*
X690533Y-517800D01*
X690133Y-516867D01*
X690333Y-516200D01*
X690733Y-515800D01*
X691333Y-515667D01*
X691933Y-515800D01*
X692533Y-516200D01*
G01X706833Y-523667D02*
X705833Y-522333D01*
X705333Y-521000D01*
Y-515667D01*
X705833Y-514333D01*
X706833Y-513000D01*
G01X715333Y-521000D02*
Y-513000D01*
G01X723333Y-515667D02*
Y-521000D01*
G01Y-513533D02*
X723133Y-513400D01*
Y-513133D01*
X723333Y-513000D01*
X723533Y-513133D01*
Y-513400D01*
X723333Y-513533D01*
G01X729633Y-521000D02*
Y-513000D01*
G01X732833Y-515667D02*
X729633Y-518733D01*
G01X730933Y-517533D02*
X733033Y-521000D01*
G01X737833Y-517400D02*
X741033D01*
X740733Y-516467D01*
X740233Y-515933D01*
X739533Y-515667D01*
X738833Y-515800D01*
X738233Y-516200D01*
X737833Y-517133D01*
X737633Y-517934D01*
Y-518733D01*
X737833Y-519533D01*
X738333Y-520333D01*
X738933Y-520867D01*
X739633Y-521000D01*
X740333Y-520733D01*
X741033Y-519934D01*
G01X753833Y-517400D02*
X757033D01*
X756733Y-516467D01*
X756233Y-515933D01*
X755533Y-515667D01*
X754833Y-515800D01*
X754233Y-516200D01*
X753833Y-517133D01*
X753633Y-517934D01*
Y-518733D01*
X753833Y-519533D01*
X754333Y-520333D01*
X754933Y-520867D01*
X755633Y-521000D01*
X756333Y-520733D01*
X757033Y-519934D01*
G01X763333Y-521000D02*
Y-513000D01*
G01X771333Y-521000D02*
Y-513000D01*
G01X779333Y-515667D02*
Y-521000D01*
G01Y-513533D02*
X779133Y-513400D01*
Y-513133D01*
X779333Y-513000D01*
X779533Y-513133D01*
Y-513400D01*
X779333Y-513533D01*
G01X785533Y-523667D02*
Y-515667D01*
G01Y-516867D02*
X786033Y-516200D01*
X786533Y-515800D01*
X787333Y-515667D01*
X788033Y-515800D01*
X788733Y-516467D01*
X789033Y-517400D01*
X789133Y-518333D01*
X789033Y-519267D01*
X788733Y-520200D01*
X788133Y-520733D01*
X787333Y-521000D01*
X786633Y-520867D01*
X785933Y-520467D01*
X785533Y-519934D01*
G01X793833Y-520067D02*
X794333Y-520600D01*
X795033Y-521000D01*
X795633D01*
X796233Y-520733D01*
X796633Y-520333D01*
X796833Y-519800D01*
X796733Y-519000D01*
X796333Y-518600D01*
X794533Y-517800D01*
X794133Y-516867D01*
X794333Y-516200D01*
X794733Y-515800D01*
X795333Y-515667D01*
X795933Y-515800D01*
X796533Y-516200D01*
G01X801833Y-517400D02*
X805033D01*
X804733Y-516467D01*
X804233Y-515933D01*
X803533Y-515667D01*
X802833Y-515800D01*
X802233Y-516200D01*
X801833Y-517133D01*
X801633Y-517934D01*
Y-518733D01*
X801833Y-519533D01*
X802333Y-520333D01*
X802933Y-520867D01*
X803633Y-521000D01*
X804333Y-520733D01*
X805033Y-519934D01*
G01X821133Y-521000D02*
Y-515667D01*
G01Y-516600D02*
X820733Y-516067D01*
X820133Y-515800D01*
X819433Y-515667D01*
X818733Y-515933D01*
X818133Y-516467D01*
X817733Y-517267D01*
X817533Y-518333D01*
X817733Y-519400D01*
X818133Y-520200D01*
X818733Y-520733D01*
X819433Y-521000D01*
X820133Y-520867D01*
X820733Y-520467D01*
X821133Y-519934D01*
G01X825633Y-521000D02*
Y-515667D01*
G01Y-517000D02*
X826033Y-516333D01*
X826633Y-515800D01*
X827433Y-515667D01*
X828133Y-515800D01*
X828733Y-516333D01*
X829033Y-517267D01*
Y-521000D01*
G01X837133Y-513000D02*
Y-521000D01*
G01Y-519800D02*
X836733Y-520467D01*
X836133Y-520867D01*
X835433Y-521000D01*
X834633Y-520733D01*
X834033Y-520067D01*
X833633Y-519267D01*
X833533Y-518333D01*
X833633Y-517400D01*
X834033Y-516600D01*
X834633Y-515933D01*
X835433Y-515667D01*
X836133Y-515800D01*
X836633Y-516067D01*
X837133Y-516600D01*
G01X851333Y-521000D02*
X850733Y-520867D01*
X850133Y-520333D01*
X849733Y-519400D01*
X849533Y-518333D01*
X849733Y-517267D01*
X850133Y-516333D01*
X850733Y-515800D01*
X851333Y-515667D01*
X851933Y-515800D01*
X852533Y-516333D01*
X852933Y-517267D01*
X853033Y-518333D01*
X852933Y-519400D01*
X852533Y-520333D01*
X851933Y-520867D01*
X851333Y-521000D01*
G01X859333Y-513000D02*
Y-521000D01*
G01X857933Y-515667D02*
X860733D01*
G01X865633Y-521000D02*
Y-513000D01*
G01Y-516867D02*
X866133Y-516200D01*
X866633Y-515800D01*
X867433Y-515667D01*
X868033Y-515800D01*
X868733Y-516333D01*
X869033Y-517133D01*
Y-521000D01*
G01X873833Y-517400D02*
X877033D01*
X876733Y-516467D01*
X876233Y-515933D01*
X875533Y-515667D01*
X874833Y-515800D01*
X874233Y-516200D01*
X873833Y-517133D01*
X873633Y-517934D01*
Y-518733D01*
X873833Y-519533D01*
X874333Y-520333D01*
X874933Y-520867D01*
X875633Y-521000D01*
X876333Y-520733D01*
X877033Y-519934D01*
G01X881933Y-521000D02*
Y-515667D01*
G01Y-516733D02*
X882433Y-516200D01*
X882933Y-515800D01*
X883633Y-515667D01*
X884133Y-515800D01*
X884733Y-516200D01*
G01X889833Y-520067D02*
X890333Y-520600D01*
X891033Y-521000D01*
X891633D01*
X892233Y-520733D01*
X892633Y-520333D01*
X892833Y-519800D01*
X892733Y-519000D01*
X892333Y-518600D01*
X890533Y-517800D01*
X890133Y-516867D01*
X890333Y-516200D01*
X890733Y-515800D01*
X891333Y-515667D01*
X891933Y-515800D01*
X892533Y-516200D01*
G01X899833Y-523667D02*
X900833Y-522333D01*
X901333Y-521000D01*
Y-515667D01*
X900833Y-514333D01*
X899833Y-513000D01*
G01X650233Y-533000D02*
Y-525000D01*
G01X654433D02*
Y-533000D01*
G01Y-529000D02*
X650233D01*
G01X660333Y-533000D02*
X659733Y-532867D01*
X659133Y-532333D01*
X658733Y-531400D01*
X658533Y-530333D01*
X658733Y-529267D01*
X659133Y-528333D01*
X659733Y-527800D01*
X660333Y-527667D01*
X660933Y-527800D01*
X661533Y-528333D01*
X661933Y-529267D01*
X662033Y-530333D01*
X661933Y-531400D01*
X661533Y-532333D01*
X660933Y-532867D01*
X660333Y-533000D01*
G01X668333D02*
Y-525000D01*
G01X674833Y-529400D02*
X678033D01*
X677733Y-528467D01*
X677233Y-527933D01*
X676533Y-527667D01*
X675833Y-527800D01*
X675233Y-528200D01*
X674833Y-529133D01*
X674633Y-529934D01*
Y-530733D01*
X674833Y-531533D01*
X675333Y-532333D01*
X675933Y-532867D01*
X676633Y-533000D01*
X677333Y-532733D01*
X678033Y-531934D01*
G01X689333Y-525000D02*
X690733Y-533000D01*
X692333Y-525000D01*
X693933Y-533000D01*
X695333Y-525000D01*
G01X702133Y-533000D02*
Y-527667D01*
G01Y-528600D02*
X701733Y-528067D01*
X701133Y-527800D01*
X700433Y-527667D01*
X699733Y-527933D01*
X699133Y-528467D01*
X698733Y-529267D01*
X698533Y-530333D01*
X698733Y-531400D01*
X699133Y-532200D01*
X699733Y-532733D01*
X700433Y-533000D01*
X701133Y-532867D01*
X701733Y-532467D01*
X702133Y-531934D01*
G01X708333Y-533000D02*
Y-525000D01*
G01X716333Y-533000D02*
Y-525000D01*
G01X730333Y-533000D02*
Y-525000D01*
X732833D01*
X733633Y-525400D01*
X734133Y-525933D01*
X734333Y-527000D01*
X734133Y-528067D01*
X733533Y-528733D01*
X732833Y-529133D01*
X730333D01*
G01X732833D02*
X734333Y-533000D01*
G01X740333D02*
X739733Y-532867D01*
X739133Y-532333D01*
X738733Y-531400D01*
X738533Y-530333D01*
X738733Y-529267D01*
X739133Y-528333D01*
X739733Y-527800D01*
X740333Y-527667D01*
X740933Y-527800D01*
X741533Y-528333D01*
X741933Y-529267D01*
X742033Y-530333D01*
X741933Y-531400D01*
X741533Y-532333D01*
X740933Y-532867D01*
X740333Y-533000D01*
G01X746633Y-527667D02*
Y-531400D01*
X747033Y-532333D01*
X747633Y-532867D01*
X748333Y-533000D01*
X749033Y-532867D01*
X749633Y-532333D01*
X750033Y-531400D01*
G01Y-533000D02*
Y-527667D01*
G01X754933Y-535000D02*
X755633Y-535533D01*
X756433Y-535667D01*
X757133Y-535533D01*
X757733Y-534867D01*
X758133Y-533933D01*
Y-527667D01*
G01Y-528733D02*
X757733Y-528200D01*
X757133Y-527800D01*
X756433Y-527667D01*
X755633Y-527933D01*
X755133Y-528467D01*
X754733Y-529400D01*
X754533Y-530333D01*
X754633Y-531133D01*
X755033Y-532067D01*
X755633Y-532733D01*
X756433Y-533000D01*
X757033Y-532867D01*
X757733Y-532333D01*
X758133Y-531800D01*
G01X762633Y-533000D02*
Y-525000D01*
G01Y-528867D02*
X763133Y-528200D01*
X763633Y-527800D01*
X764433Y-527667D01*
X765033Y-527800D01*
X765733Y-528333D01*
X766033Y-529133D01*
Y-533000D01*
G01X770633D02*
Y-527667D01*
G01Y-529000D02*
X771033Y-528333D01*
X771633Y-527800D01*
X772433Y-527667D01*
X773133Y-527800D01*
X773733Y-528333D01*
X774033Y-529267D01*
Y-533000D01*
G01X778833Y-529400D02*
X782033D01*
X781733Y-528467D01*
X781233Y-527933D01*
X780533Y-527667D01*
X779833Y-527800D01*
X779233Y-528200D01*
X778833Y-529133D01*
X778633Y-529934D01*
Y-530733D01*
X778833Y-531533D01*
X779333Y-532333D01*
X779933Y-532867D01*
X780633Y-533000D01*
X781333Y-532733D01*
X782033Y-531934D01*
G01X786833Y-532067D02*
X787333Y-532600D01*
X788033Y-533000D01*
X788633D01*
X789233Y-532733D01*
X789633Y-532333D01*
X789833Y-531800D01*
X789733Y-531000D01*
X789333Y-530600D01*
X787533Y-529800D01*
X787133Y-528867D01*
X787333Y-528200D01*
X787733Y-527800D01*
X788333Y-527667D01*
X788933Y-527800D01*
X789533Y-528200D01*
G01X794833Y-532067D02*
X795333Y-532600D01*
X796033Y-533000D01*
X796633D01*
X797233Y-532733D01*
X797633Y-532333D01*
X797833Y-531800D01*
X797733Y-531000D01*
X797333Y-530600D01*
X795533Y-529800D01*
X795133Y-528867D01*
X795333Y-528200D01*
X795733Y-527800D01*
X796333Y-527667D01*
X796933Y-527800D01*
X797533Y-528200D01*
G01X649133Y-450500D02*
Y-456233D01*
X649533Y-457434D01*
X650333Y-458233D01*
X651333Y-458500D01*
X652333Y-458233D01*
X653133Y-457434D01*
X653533Y-456233D01*
Y-450500D01*
G01X657633Y-458500D02*
Y-453167D01*
G01Y-454500D02*
X658033Y-453833D01*
X658633Y-453300D01*
X659433Y-453167D01*
X660133Y-453300D01*
X660733Y-453833D01*
X661033Y-454767D01*
Y-458500D01*
G01X666033Y-455833D02*
X668633D01*
G01X673533Y-461167D02*
Y-453167D01*
G01Y-454367D02*
X674033Y-453700D01*
X674533Y-453300D01*
X675333Y-453167D01*
X676033Y-453300D01*
X676733Y-453967D01*
X677033Y-454900D01*
X677133Y-455833D01*
X677033Y-456767D01*
X676733Y-457700D01*
X676133Y-458233D01*
X675333Y-458500D01*
X674633Y-458367D01*
X673933Y-457967D01*
X673533Y-457434D01*
G01X683333Y-458500D02*
Y-450500D01*
G01X689633Y-453167D02*
Y-456900D01*
X690033Y-457833D01*
X690633Y-458367D01*
X691333Y-458500D01*
X692033Y-458367D01*
X692633Y-457833D01*
X693033Y-456900D01*
G01Y-458500D02*
Y-453167D01*
G01X697933Y-460500D02*
X698633Y-461033D01*
X699433Y-461167D01*
X700133Y-461033D01*
X700733Y-460367D01*
X701133Y-459433D01*
Y-453167D01*
G01Y-454233D02*
X700733Y-453700D01*
X700133Y-453300D01*
X699433Y-453167D01*
X698633Y-453433D01*
X698133Y-453967D01*
X697733Y-454900D01*
X697533Y-455833D01*
X697633Y-456633D01*
X698033Y-457567D01*
X698633Y-458233D01*
X699433Y-458500D01*
X700033Y-458367D01*
X700733Y-457833D01*
X701133Y-457300D01*
G01X705933Y-460500D02*
X706633Y-461033D01*
X707433Y-461167D01*
X708133Y-461033D01*
X708733Y-460367D01*
X709133Y-459433D01*
Y-453167D01*
G01Y-454233D02*
X708733Y-453700D01*
X708133Y-453300D01*
X707433Y-453167D01*
X706633Y-453433D01*
X706133Y-453967D01*
X705733Y-454900D01*
X705533Y-455833D01*
X705633Y-456633D01*
X706033Y-457567D01*
X706633Y-458233D01*
X707433Y-458500D01*
X708033Y-458367D01*
X708733Y-457833D01*
X709133Y-457300D01*
G01X713833Y-454900D02*
X717033D01*
X716733Y-453967D01*
X716233Y-453433D01*
X715533Y-453167D01*
X714833Y-453300D01*
X714233Y-453700D01*
X713833Y-454633D01*
X713633Y-455434D01*
Y-456233D01*
X713833Y-457033D01*
X714333Y-457833D01*
X714933Y-458367D01*
X715633Y-458500D01*
X716333Y-458233D01*
X717033Y-457434D01*
G01X725133Y-450500D02*
Y-458500D01*
G01Y-457300D02*
X724733Y-457967D01*
X724133Y-458367D01*
X723433Y-458500D01*
X722633Y-458233D01*
X722033Y-457567D01*
X721633Y-456767D01*
X721533Y-455833D01*
X721633Y-454900D01*
X722033Y-454100D01*
X722633Y-453433D01*
X723433Y-453167D01*
X724133Y-453300D01*
X724633Y-453567D01*
X725133Y-454100D01*
G01X737333Y-458500D02*
Y-450500D01*
X739733D01*
X740533Y-450900D01*
X741133Y-451833D01*
X741333Y-452900D01*
X741133Y-453967D01*
X740633Y-454767D01*
X739733Y-455167D01*
X737333D01*
G01X747333Y-450500D02*
Y-458500D01*
G01X745033Y-450500D02*
X749633D01*
G01X753233Y-458500D02*
Y-450500D01*
G01X757433D02*
Y-458500D01*
G01Y-454500D02*
X753233D01*
G01X770833Y-461167D02*
X769833Y-459833D01*
X769333Y-458500D01*
Y-453167D01*
X769833Y-451833D01*
X770833Y-450500D01*
G01X777233Y-458500D02*
Y-450500D01*
G01X781433D02*
Y-458500D01*
G01Y-454500D02*
X777233D01*
G01X787333Y-458500D02*
X786733Y-458367D01*
X786133Y-457833D01*
X785733Y-456900D01*
X785533Y-455833D01*
X785733Y-454767D01*
X786133Y-453833D01*
X786733Y-453300D01*
X787333Y-453167D01*
X787933Y-453300D01*
X788533Y-453833D01*
X788933Y-454767D01*
X789033Y-455833D01*
X788933Y-456900D01*
X788533Y-457833D01*
X787933Y-458367D01*
X787333Y-458500D01*
G01X795333D02*
Y-450500D01*
G01X801833Y-454900D02*
X805033D01*
X804733Y-453967D01*
X804233Y-453433D01*
X803533Y-453167D01*
X802833Y-453300D01*
X802233Y-453700D01*
X801833Y-454633D01*
X801633Y-455434D01*
Y-456233D01*
X801833Y-457033D01*
X802333Y-457833D01*
X802933Y-458367D01*
X803633Y-458500D01*
X804333Y-458233D01*
X805033Y-457434D01*
G01X817233D02*
X818033Y-458100D01*
X818933Y-458500D01*
X819733D01*
X820533Y-458100D01*
X821133Y-457434D01*
X821433Y-456500D01*
X821233Y-455567D01*
X820733Y-454767D01*
X819833Y-454233D01*
X818633Y-453967D01*
X817933Y-453433D01*
X817633Y-452500D01*
X817833Y-451567D01*
X818333Y-450900D01*
X819033Y-450500D01*
X819733D01*
X820433Y-450767D01*
X821033Y-451433D01*
G01X827333Y-453167D02*
Y-458500D01*
G01Y-451033D02*
X827133Y-450900D01*
Y-450633D01*
X827333Y-450500D01*
X827533Y-450633D01*
Y-450900D01*
X827333Y-451033D01*
G01X833833Y-453167D02*
X836833D01*
X833833Y-458500D01*
X836833D01*
G01X841833Y-454900D02*
X845033D01*
X844733Y-453967D01*
X844233Y-453433D01*
X843533Y-453167D01*
X842833Y-453300D01*
X842233Y-453700D01*
X841833Y-454633D01*
X841633Y-455434D01*
Y-456233D01*
X841833Y-457033D01*
X842333Y-457833D01*
X842933Y-458367D01*
X843633Y-458500D01*
X844333Y-458233D01*
X845033Y-457434D01*
G01X853333Y-458500D02*
X849333Y-455833D01*
X853333Y-453167D01*
G01X859333Y-458500D02*
Y-450500D01*
X858133Y-452100D01*
G01Y-458500D02*
X860533D01*
G01X865633Y-457567D02*
X866333Y-458233D01*
X867133Y-458500D01*
X867933Y-458233D01*
X868633Y-457434D01*
X869133Y-456233D01*
X869333Y-455033D01*
Y-453567D01*
X869133Y-452367D01*
X868633Y-451300D01*
X868033Y-450767D01*
X867333Y-450500D01*
X866533Y-450767D01*
X865933Y-451300D01*
X865533Y-452100D01*
X865333Y-453167D01*
X865533Y-454100D01*
X866033Y-455033D01*
X866633Y-455567D01*
X867333Y-455700D01*
X868133Y-455434D01*
X868733Y-454767D01*
X869333Y-453567D01*
G01X875133Y-458500D02*
X875333Y-456767D01*
X875633Y-455300D01*
X876033Y-453967D01*
X876533Y-452500D01*
X877333Y-450500D01*
X873333D01*
G01X880333Y-458500D02*
Y-453167D01*
G01Y-454633D02*
X880633Y-453967D01*
X881133Y-453433D01*
X881833Y-453167D01*
X882533Y-453433D01*
X883033Y-453967D01*
X883333Y-454633D01*
Y-458500D01*
G01Y-454633D02*
X883633Y-453967D01*
X884133Y-453433D01*
X884833Y-453167D01*
X885533Y-453433D01*
X886033Y-453967D01*
X886333Y-454767D01*
Y-458500D01*
G01X891333Y-453167D02*
Y-458500D01*
G01Y-451033D02*
X891133Y-450900D01*
Y-450633D01*
X891333Y-450500D01*
X891533Y-450633D01*
Y-450900D01*
X891333Y-451033D01*
G01X899333Y-458500D02*
Y-450500D01*
G01X912833Y-453167D02*
X914033Y-458500D01*
X915333Y-453167D01*
X916633Y-458500D01*
X917833Y-453167D01*
G01X923333D02*
Y-458500D01*
G01Y-451033D02*
X923133Y-450900D01*
Y-450633D01*
X923333Y-450500D01*
X923533Y-450633D01*
Y-450900D01*
X923333Y-451033D01*
G01X931333Y-450500D02*
Y-458500D01*
G01X929933Y-453167D02*
X932733D01*
G01X937633Y-458500D02*
Y-450500D01*
G01Y-454367D02*
X938133Y-453700D01*
X938633Y-453300D01*
X939433Y-453167D01*
X940033Y-453300D01*
X940733Y-453833D01*
X941033Y-454633D01*
Y-458500D01*
G01X953233D02*
Y-450500D01*
G01X957433D02*
Y-458500D01*
G01Y-454500D02*
X953233D01*
G01X960833Y-458500D02*
X963333Y-450500D01*
X965833Y-458500D01*
G01X964933Y-455700D02*
X961733D01*
G01X969233Y-457434D02*
X970033Y-458100D01*
X970933Y-458500D01*
X971733D01*
X972533Y-458100D01*
X973133Y-457434D01*
X973433Y-456500D01*
X973233Y-455567D01*
X972733Y-454767D01*
X971833Y-454233D01*
X970633Y-453967D01*
X969933Y-453433D01*
X969633Y-452500D01*
X969833Y-451567D01*
X970333Y-450900D01*
X971033Y-450500D01*
X971733D01*
X972433Y-450767D01*
X973033Y-451433D01*
G01X977333Y-450500D02*
Y-458500D01*
X981333D01*
G01X993533Y-461167D02*
Y-453167D01*
G01Y-454367D02*
X994033Y-453700D01*
X994533Y-453300D01*
X995333Y-453167D01*
X996033Y-453300D01*
X996733Y-453967D01*
X997033Y-454900D01*
X997133Y-455833D01*
X997033Y-456767D01*
X996733Y-457700D01*
X996133Y-458233D01*
X995333Y-458500D01*
X994633Y-458367D01*
X993933Y-457967D01*
X993533Y-457434D01*
G01X1001933Y-458500D02*
Y-453167D01*
G01Y-454233D02*
X1002433Y-453700D01*
X1002933Y-453300D01*
X1003633Y-453167D01*
X1004133Y-453300D01*
X1004733Y-453700D01*
G01X1011333Y-458500D02*
X1010733Y-458367D01*
X1010133Y-457833D01*
X1009733Y-456900D01*
X1009533Y-455833D01*
X1009733Y-454767D01*
X1010133Y-453833D01*
X1010733Y-453300D01*
X1011333Y-453167D01*
X1011933Y-453300D01*
X1012533Y-453833D01*
X1012933Y-454767D01*
X1013033Y-455833D01*
X1012933Y-456900D01*
X1012533Y-457833D01*
X1011933Y-458367D01*
X1011333Y-458500D01*
G01X1021133Y-450500D02*
Y-458500D01*
G01Y-457300D02*
X1020733Y-457967D01*
X1020133Y-458367D01*
X1019433Y-458500D01*
X1018633Y-458233D01*
X1018033Y-457567D01*
X1017633Y-456767D01*
X1017533Y-455833D01*
X1017633Y-454900D01*
X1018033Y-454100D01*
X1018633Y-453433D01*
X1019433Y-453167D01*
X1020133Y-453300D01*
X1020633Y-453567D01*
X1021133Y-454100D01*
G01X1025633Y-453167D02*
Y-456900D01*
X1026033Y-457833D01*
X1026633Y-458367D01*
X1027333Y-458500D01*
X1028033Y-458367D01*
X1028633Y-457833D01*
X1029033Y-456900D01*
G01Y-458500D02*
Y-453167D01*
G01X1036933Y-453833D02*
X1036233Y-453300D01*
X1035633Y-453167D01*
X1034833Y-453433D01*
X1034233Y-453967D01*
X1033833Y-454900D01*
X1033733Y-455833D01*
X1033833Y-456767D01*
X1034233Y-457567D01*
X1034833Y-458233D01*
X1035633Y-458500D01*
X1036333Y-458233D01*
X1036933Y-457700D01*
G01X1043333Y-450500D02*
Y-458500D01*
G01X1041933Y-453167D02*
X1044733D01*
G01X1049833Y-457567D02*
X1050333Y-458100D01*
X1051033Y-458500D01*
X1051633D01*
X1052233Y-458233D01*
X1052633Y-457833D01*
X1052833Y-457300D01*
X1052733Y-456500D01*
X1052333Y-456100D01*
X1050533Y-455300D01*
X1050133Y-454367D01*
X1050333Y-453700D01*
X1050733Y-453300D01*
X1051333Y-453167D01*
X1051933Y-453300D01*
X1052533Y-453700D01*
G01X1059833Y-461167D02*
X1060833Y-459833D01*
X1061333Y-458500D01*
Y-453167D01*
X1060833Y-451833D01*
X1059833Y-450500D01*
G01X649133Y-438000D02*
Y-443733D01*
X649533Y-444934D01*
X650333Y-445733D01*
X651333Y-446000D01*
X652333Y-445733D01*
X653133Y-444934D01*
X653533Y-443733D01*
Y-438000D01*
G01X657633Y-446000D02*
Y-440667D01*
G01Y-442000D02*
X658033Y-441333D01*
X658633Y-440800D01*
X659433Y-440667D01*
X660133Y-440800D01*
X660733Y-441333D01*
X661033Y-442267D01*
Y-446000D01*
G01X666033Y-443333D02*
X668633D01*
G01X673533Y-448667D02*
Y-440667D01*
G01Y-441867D02*
X674033Y-441200D01*
X674533Y-440800D01*
X675333Y-440667D01*
X676033Y-440800D01*
X676733Y-441467D01*
X677033Y-442400D01*
X677133Y-443333D01*
X677033Y-444267D01*
X676733Y-445200D01*
X676133Y-445733D01*
X675333Y-446000D01*
X674633Y-445867D01*
X673933Y-445467D01*
X673533Y-444934D01*
G01X683333Y-446000D02*
Y-438000D01*
G01X689633Y-440667D02*
Y-444400D01*
X690033Y-445333D01*
X690633Y-445867D01*
X691333Y-446000D01*
X692033Y-445867D01*
X692633Y-445333D01*
X693033Y-444400D01*
G01Y-446000D02*
Y-440667D01*
G01X697933Y-448000D02*
X698633Y-448533D01*
X699433Y-448667D01*
X700133Y-448533D01*
X700733Y-447867D01*
X701133Y-446933D01*
Y-440667D01*
G01Y-441733D02*
X700733Y-441200D01*
X700133Y-440800D01*
X699433Y-440667D01*
X698633Y-440933D01*
X698133Y-441467D01*
X697733Y-442400D01*
X697533Y-443333D01*
X697633Y-444133D01*
X698033Y-445067D01*
X698633Y-445733D01*
X699433Y-446000D01*
X700033Y-445867D01*
X700733Y-445333D01*
X701133Y-444800D01*
G01X705933Y-448000D02*
X706633Y-448533D01*
X707433Y-448667D01*
X708133Y-448533D01*
X708733Y-447867D01*
X709133Y-446933D01*
Y-440667D01*
G01Y-441733D02*
X708733Y-441200D01*
X708133Y-440800D01*
X707433Y-440667D01*
X706633Y-440933D01*
X706133Y-441467D01*
X705733Y-442400D01*
X705533Y-443333D01*
X705633Y-444133D01*
X706033Y-445067D01*
X706633Y-445733D01*
X707433Y-446000D01*
X708033Y-445867D01*
X708733Y-445333D01*
X709133Y-444800D01*
G01X713833Y-442400D02*
X717033D01*
X716733Y-441467D01*
X716233Y-440933D01*
X715533Y-440667D01*
X714833Y-440800D01*
X714233Y-441200D01*
X713833Y-442133D01*
X713633Y-442934D01*
Y-443733D01*
X713833Y-444533D01*
X714333Y-445333D01*
X714933Y-445867D01*
X715633Y-446000D01*
X716333Y-445733D01*
X717033Y-444934D01*
G01X725133Y-438000D02*
Y-446000D01*
G01Y-444800D02*
X724733Y-445467D01*
X724133Y-445867D01*
X723433Y-446000D01*
X722633Y-445733D01*
X722033Y-445067D01*
X721633Y-444267D01*
X721533Y-443333D01*
X721633Y-442400D01*
X722033Y-441600D01*
X722633Y-440933D01*
X723433Y-440667D01*
X724133Y-440800D01*
X724633Y-441067D01*
X725133Y-441600D01*
G01X737333Y-446000D02*
Y-438000D01*
X739733D01*
X740533Y-438400D01*
X741133Y-439333D01*
X741333Y-440400D01*
X741133Y-441467D01*
X740633Y-442267D01*
X739733Y-442667D01*
X737333D01*
G01X747333Y-438000D02*
Y-446000D01*
G01X745033Y-438000D02*
X749633D01*
G01X753233Y-446000D02*
Y-438000D01*
G01X757433D02*
Y-446000D01*
G01Y-442000D02*
X753233D01*
G01X770833Y-448667D02*
X769833Y-447333D01*
X769333Y-446000D01*
Y-440667D01*
X769833Y-439333D01*
X770833Y-438000D01*
G01X777233Y-446000D02*
Y-438000D01*
G01X781433D02*
Y-446000D01*
G01Y-442000D02*
X777233D01*
G01X787333Y-446000D02*
X786733Y-445867D01*
X786133Y-445333D01*
X785733Y-444400D01*
X785533Y-443333D01*
X785733Y-442267D01*
X786133Y-441333D01*
X786733Y-440800D01*
X787333Y-440667D01*
X787933Y-440800D01*
X788533Y-441333D01*
X788933Y-442267D01*
X789033Y-443333D01*
X788933Y-444400D01*
X788533Y-445333D01*
X787933Y-445867D01*
X787333Y-446000D01*
G01X795333D02*
Y-438000D01*
G01X801833Y-442400D02*
X805033D01*
X804733Y-441467D01*
X804233Y-440933D01*
X803533Y-440667D01*
X802833Y-440800D01*
X802233Y-441200D01*
X801833Y-442133D01*
X801633Y-442934D01*
Y-443733D01*
X801833Y-444533D01*
X802333Y-445333D01*
X802933Y-445867D01*
X803633Y-446000D01*
X804333Y-445733D01*
X805033Y-444934D01*
G01X817233D02*
X818033Y-445600D01*
X818933Y-446000D01*
X819733D01*
X820533Y-445600D01*
X821133Y-444934D01*
X821433Y-444000D01*
X821233Y-443067D01*
X820733Y-442267D01*
X819833Y-441733D01*
X818633Y-441467D01*
X817933Y-440933D01*
X817633Y-440000D01*
X817833Y-439067D01*
X818333Y-438400D01*
X819033Y-438000D01*
X819733D01*
X820433Y-438267D01*
X821033Y-438933D01*
G01X827333Y-440667D02*
Y-446000D01*
G01Y-438533D02*
X827133Y-438400D01*
Y-438133D01*
X827333Y-438000D01*
X827533Y-438133D01*
Y-438400D01*
X827333Y-438533D01*
G01X833833Y-440667D02*
X836833D01*
X833833Y-446000D01*
X836833D01*
G01X841833Y-442400D02*
X845033D01*
X844733Y-441467D01*
X844233Y-440933D01*
X843533Y-440667D01*
X842833Y-440800D01*
X842233Y-441200D01*
X841833Y-442133D01*
X841633Y-442934D01*
Y-443733D01*
X841833Y-444533D01*
X842333Y-445333D01*
X842933Y-445867D01*
X843633Y-446000D01*
X844333Y-445733D01*
X845033Y-444934D01*
G01X853333Y-446000D02*
X849333Y-443333D01*
X853333Y-440667D01*
G01X859333Y-446000D02*
Y-438000D01*
X858133Y-439600D01*
G01Y-446000D02*
X860533D01*
G01X865633Y-445067D02*
X866333Y-445733D01*
X867133Y-446000D01*
X867933Y-445733D01*
X868633Y-444934D01*
X869133Y-443733D01*
X869333Y-442533D01*
Y-441067D01*
X869133Y-439867D01*
X868633Y-438800D01*
X868033Y-438267D01*
X867333Y-438000D01*
X866533Y-438267D01*
X865933Y-438800D01*
X865533Y-439600D01*
X865333Y-440667D01*
X865533Y-441600D01*
X866033Y-442533D01*
X866633Y-443067D01*
X867333Y-443200D01*
X868133Y-442934D01*
X868733Y-442267D01*
X869333Y-441067D01*
G01X875133Y-446000D02*
X875333Y-444267D01*
X875633Y-442800D01*
X876033Y-441467D01*
X876533Y-440000D01*
X877333Y-438000D01*
X873333D01*
G01X880333Y-446000D02*
Y-440667D01*
G01Y-442133D02*
X880633Y-441467D01*
X881133Y-440933D01*
X881833Y-440667D01*
X882533Y-440933D01*
X883033Y-441467D01*
X883333Y-442133D01*
Y-446000D01*
G01Y-442133D02*
X883633Y-441467D01*
X884133Y-440933D01*
X884833Y-440667D01*
X885533Y-440933D01*
X886033Y-441467D01*
X886333Y-442267D01*
Y-446000D01*
G01X891333Y-440667D02*
Y-446000D01*
G01Y-438533D02*
X891133Y-438400D01*
Y-438133D01*
X891333Y-438000D01*
X891533Y-438133D01*
Y-438400D01*
X891333Y-438533D01*
G01X899333Y-446000D02*
Y-438000D01*
G01X912833Y-440667D02*
X914033Y-446000D01*
X915333Y-440667D01*
X916633Y-446000D01*
X917833Y-440667D01*
G01X923333D02*
Y-446000D01*
G01Y-438533D02*
X923133Y-438400D01*
Y-438133D01*
X923333Y-438000D01*
X923533Y-438133D01*
Y-438400D01*
X923333Y-438533D01*
G01X931333Y-438000D02*
Y-446000D01*
G01X929933Y-440667D02*
X932733D01*
G01X937633Y-446000D02*
Y-438000D01*
G01Y-441867D02*
X938133Y-441200D01*
X938633Y-440800D01*
X939433Y-440667D01*
X940033Y-440800D01*
X940733Y-441333D01*
X941033Y-442133D01*
Y-446000D01*
G01X953633D02*
Y-440667D01*
G01Y-442000D02*
X954033Y-441333D01*
X954633Y-440800D01*
X955433Y-440667D01*
X956133Y-440800D01*
X956733Y-441333D01*
X957033Y-442267D01*
Y-446000D01*
G01X963333D02*
X962733Y-445867D01*
X962133Y-445333D01*
X961733Y-444400D01*
X961533Y-443333D01*
X961733Y-442267D01*
X962133Y-441333D01*
X962733Y-440800D01*
X963333Y-440667D01*
X963933Y-440800D01*
X964533Y-441333D01*
X964933Y-442267D01*
X965033Y-443333D01*
X964933Y-444400D01*
X964533Y-445333D01*
X963933Y-445867D01*
X963333Y-446000D01*
G01X969633D02*
Y-440667D01*
G01Y-442000D02*
X970033Y-441333D01*
X970633Y-440800D01*
X971433Y-440667D01*
X972133Y-440800D01*
X972733Y-441333D01*
X973033Y-442267D01*
Y-446000D01*
G01X978033Y-443333D02*
X980633D01*
G01X985233Y-446000D02*
Y-438000D01*
G01X989433D02*
Y-446000D01*
G01Y-442000D02*
X985233D01*
G01X992833Y-446000D02*
X995333Y-438000D01*
X997833Y-446000D01*
G01X996933Y-443200D02*
X993733D01*
G01X1001233Y-444934D02*
X1002033Y-445600D01*
X1002933Y-446000D01*
X1003733D01*
X1004533Y-445600D01*
X1005133Y-444934D01*
X1005433Y-444000D01*
X1005233Y-443067D01*
X1004733Y-442267D01*
X1003833Y-441733D01*
X1002633Y-441467D01*
X1001933Y-440933D01*
X1001633Y-440000D01*
X1001833Y-439067D01*
X1002333Y-438400D01*
X1003033Y-438000D01*
X1003733D01*
X1004433Y-438267D01*
X1005033Y-438933D01*
G01X1009333Y-438000D02*
Y-446000D01*
X1013333D01*
G01X1025533Y-448667D02*
Y-440667D01*
G01Y-441867D02*
X1026033Y-441200D01*
X1026533Y-440800D01*
X1027333Y-440667D01*
X1028033Y-440800D01*
X1028733Y-441467D01*
X1029033Y-442400D01*
X1029133Y-443333D01*
X1029033Y-444267D01*
X1028733Y-445200D01*
X1028133Y-445733D01*
X1027333Y-446000D01*
X1026633Y-445867D01*
X1025933Y-445467D01*
X1025533Y-444934D01*
G01X1033933Y-446000D02*
Y-440667D01*
G01Y-441733D02*
X1034433Y-441200D01*
X1034933Y-440800D01*
X1035633Y-440667D01*
X1036133Y-440800D01*
X1036733Y-441200D01*
G01X1043333Y-446000D02*
X1042733Y-445867D01*
X1042133Y-445333D01*
X1041733Y-444400D01*
X1041533Y-443333D01*
X1041733Y-442267D01*
X1042133Y-441333D01*
X1042733Y-440800D01*
X1043333Y-440667D01*
X1043933Y-440800D01*
X1044533Y-441333D01*
X1044933Y-442267D01*
X1045033Y-443333D01*
X1044933Y-444400D01*
X1044533Y-445333D01*
X1043933Y-445867D01*
X1043333Y-446000D01*
G01X1053133Y-438000D02*
Y-446000D01*
G01Y-444800D02*
X1052733Y-445467D01*
X1052133Y-445867D01*
X1051433Y-446000D01*
X1050633Y-445733D01*
X1050033Y-445067D01*
X1049633Y-444267D01*
X1049533Y-443333D01*
X1049633Y-442400D01*
X1050033Y-441600D01*
X1050633Y-440933D01*
X1051433Y-440667D01*
X1052133Y-440800D01*
X1052633Y-441067D01*
X1053133Y-441600D01*
G01X1057633Y-440667D02*
Y-444400D01*
X1058033Y-445333D01*
X1058633Y-445867D01*
X1059333Y-446000D01*
X1060033Y-445867D01*
X1060633Y-445333D01*
X1061033Y-444400D01*
G01Y-446000D02*
Y-440667D01*
G01X1068933Y-441333D02*
X1068233Y-440800D01*
X1067633Y-440667D01*
X1066833Y-440933D01*
X1066233Y-441467D01*
X1065833Y-442400D01*
X1065733Y-443333D01*
X1065833Y-444267D01*
X1066233Y-445067D01*
X1066833Y-445733D01*
X1067633Y-446000D01*
X1068333Y-445733D01*
X1068933Y-445200D01*
G01X1075333Y-438000D02*
Y-446000D01*
G01X1073933Y-440667D02*
X1076733D01*
G01X1081833Y-445067D02*
X1082333Y-445600D01*
X1083033Y-446000D01*
X1083633D01*
X1084233Y-445733D01*
X1084633Y-445333D01*
X1084833Y-444800D01*
X1084733Y-444000D01*
X1084333Y-443600D01*
X1082533Y-442800D01*
X1082133Y-441867D01*
X1082333Y-441200D01*
X1082733Y-440800D01*
X1083333Y-440667D01*
X1083933Y-440800D01*
X1084533Y-441200D01*
G01X1091833Y-448667D02*
X1092833Y-447333D01*
X1093333Y-446000D01*
Y-440667D01*
X1092833Y-439333D01*
X1091833Y-438000D01*
G01X649533Y-471000D02*
Y-463000D01*
X654133Y-471000D01*
Y-463000D01*
G01X657833Y-471000D02*
Y-463000D01*
X660233D01*
X661033Y-463400D01*
X661633Y-464333D01*
X661833Y-465400D01*
X661633Y-466467D01*
X661133Y-467267D01*
X660233Y-467667D01*
X657833D01*
G01X667833Y-463000D02*
Y-471000D01*
G01X665533Y-463000D02*
X670133D01*
G01X673733Y-471000D02*
Y-463000D01*
G01X677933D02*
Y-471000D01*
G01Y-467000D02*
X673733D01*
G01X689733Y-469934D02*
X690533Y-470600D01*
X691433Y-471000D01*
X692233D01*
X693033Y-470600D01*
X693633Y-469934D01*
X693933Y-469000D01*
X693733Y-468067D01*
X693233Y-467267D01*
X692333Y-466733D01*
X691133Y-466467D01*
X690433Y-465933D01*
X690133Y-465000D01*
X690333Y-464067D01*
X690833Y-463400D01*
X691533Y-463000D01*
X692233D01*
X692933Y-463267D01*
X693533Y-463933D01*
G01X699833Y-465667D02*
Y-471000D01*
G01Y-463533D02*
X699633Y-463400D01*
Y-463133D01*
X699833Y-463000D01*
X700033Y-463133D01*
Y-463400D01*
X699833Y-463533D01*
G01X706333Y-465667D02*
X709333D01*
X706333Y-471000D01*
X709333D01*
G01X714333Y-467400D02*
X717533D01*
X717233Y-466467D01*
X716733Y-465933D01*
X716033Y-465667D01*
X715333Y-465800D01*
X714733Y-466200D01*
X714333Y-467133D01*
X714133Y-467934D01*
Y-468733D01*
X714333Y-469533D01*
X714833Y-470333D01*
X715433Y-470867D01*
X716133Y-471000D01*
X716833Y-470733D01*
X717533Y-469934D01*
G01X725833Y-471000D02*
X721833Y-468333D01*
X725833Y-465667D01*
G01X737633Y-469800D02*
X738233Y-470467D01*
X738933Y-470867D01*
X739833Y-471000D01*
X740733Y-470733D01*
X741433Y-470200D01*
X741933Y-469267D01*
X742033Y-468200D01*
X741833Y-467133D01*
X741333Y-466467D01*
X740633Y-465933D01*
X739933Y-465800D01*
X739233Y-465933D01*
X738333Y-466467D01*
X738633Y-463000D01*
X741333D01*
G01X744833Y-471000D02*
Y-465667D01*
G01Y-467133D02*
X745133Y-466467D01*
X745633Y-465933D01*
X746333Y-465667D01*
X747033Y-465933D01*
X747533Y-466467D01*
X747833Y-467133D01*
Y-471000D01*
G01Y-467133D02*
X748133Y-466467D01*
X748633Y-465933D01*
X749333Y-465667D01*
X750033Y-465933D01*
X750533Y-466467D01*
X750833Y-467267D01*
Y-471000D01*
G01X752833D02*
Y-465667D01*
G01Y-467133D02*
X753133Y-466467D01*
X753633Y-465933D01*
X754333Y-465667D01*
X755033Y-465933D01*
X755533Y-466467D01*
X755833Y-467133D01*
Y-471000D01*
G01Y-467133D02*
X756133Y-466467D01*
X756633Y-465933D01*
X757333Y-465667D01*
X758033Y-465933D01*
X758533Y-466467D01*
X758833Y-467267D01*
Y-471000D01*
G01X771333Y-473667D02*
X770333Y-472333D01*
X769833Y-471000D01*
Y-465667D01*
X770333Y-464333D01*
X771333Y-463000D01*
G01X778133Y-471000D02*
Y-465667D01*
G01Y-467000D02*
X778533Y-466333D01*
X779133Y-465800D01*
X779933Y-465667D01*
X780633Y-465800D01*
X781233Y-466333D01*
X781533Y-467267D01*
Y-471000D01*
G01X787833D02*
X787233Y-470867D01*
X786633Y-470333D01*
X786233Y-469400D01*
X786033Y-468333D01*
X786233Y-467267D01*
X786633Y-466333D01*
X787233Y-465800D01*
X787833Y-465667D01*
X788433Y-465800D01*
X789033Y-466333D01*
X789433Y-467267D01*
X789533Y-468333D01*
X789433Y-469400D01*
X789033Y-470333D01*
X788433Y-470867D01*
X787833Y-471000D01*
G01X795833Y-463000D02*
Y-471000D01*
G01X794433Y-465667D02*
X797233D01*
G01X811833Y-471000D02*
X811233Y-470867D01*
X810633Y-470333D01*
X810233Y-469400D01*
X810033Y-468333D01*
X810233Y-467267D01*
X810633Y-466333D01*
X811233Y-465800D01*
X811833Y-465667D01*
X812433Y-465800D01*
X813033Y-466333D01*
X813433Y-467267D01*
X813533Y-468333D01*
X813433Y-469400D01*
X813033Y-470333D01*
X812433Y-470867D01*
X811833Y-471000D01*
G01X818133D02*
Y-465667D01*
G01Y-467000D02*
X818533Y-466333D01*
X819133Y-465800D01*
X819933Y-465667D01*
X820633Y-465800D01*
X821233Y-466333D01*
X821533Y-467267D01*
Y-471000D01*
G01X834033D02*
Y-463000D01*
G01Y-467000D02*
X834533Y-466200D01*
X835133Y-465800D01*
X835733Y-465667D01*
X836633Y-465933D01*
X837233Y-466467D01*
X837633Y-467400D01*
Y-468467D01*
X837433Y-469533D01*
X837033Y-470333D01*
X836333Y-470867D01*
X835733Y-471000D01*
X835133Y-470867D01*
X834533Y-470467D01*
X834033Y-469800D01*
G01X842433Y-471000D02*
Y-465667D01*
G01Y-466733D02*
X842933Y-466200D01*
X843433Y-465800D01*
X844133Y-465667D01*
X844633Y-465800D01*
X845233Y-466200D01*
G01X850333Y-467400D02*
X853533D01*
X853233Y-466467D01*
X852733Y-465933D01*
X852033Y-465667D01*
X851333Y-465800D01*
X850733Y-466200D01*
X850333Y-467133D01*
X850133Y-467934D01*
Y-468733D01*
X850333Y-469533D01*
X850833Y-470333D01*
X851433Y-470867D01*
X852133Y-471000D01*
X852833Y-470733D01*
X853533Y-469934D01*
G01X861633Y-471000D02*
Y-465667D01*
G01Y-466600D02*
X861233Y-466067D01*
X860633Y-465800D01*
X859933Y-465667D01*
X859233Y-465933D01*
X858633Y-466467D01*
X858233Y-467267D01*
X858033Y-468333D01*
X858233Y-469400D01*
X858633Y-470200D01*
X859233Y-470733D01*
X859933Y-471000D01*
X860633Y-470867D01*
X861233Y-470467D01*
X861633Y-469934D01*
G01X866133Y-471000D02*
Y-463000D01*
G01X869333Y-465667D02*
X866133Y-468733D01*
G01X867433Y-467533D02*
X869533Y-471000D01*
G01X877633D02*
Y-465667D01*
G01Y-466600D02*
X877233Y-466067D01*
X876633Y-465800D01*
X875933Y-465667D01*
X875233Y-465933D01*
X874633Y-466467D01*
X874233Y-467267D01*
X874033Y-468333D01*
X874233Y-469400D01*
X874633Y-470200D01*
X875233Y-470733D01*
X875933Y-471000D01*
X876633Y-470867D01*
X877233Y-470467D01*
X877633Y-469934D01*
G01X881333Y-465667D02*
X882533Y-471000D01*
X883833Y-465667D01*
X885133Y-471000D01*
X886333Y-465667D01*
G01X893633Y-471000D02*
Y-465667D01*
G01Y-466600D02*
X893233Y-466067D01*
X892633Y-465800D01*
X891933Y-465667D01*
X891233Y-465933D01*
X890633Y-466467D01*
X890233Y-467267D01*
X890033Y-468333D01*
X890233Y-469400D01*
X890633Y-470200D01*
X891233Y-470733D01*
X891933Y-471000D01*
X892633Y-470867D01*
X893233Y-470467D01*
X893633Y-469934D01*
G01X897733Y-473400D02*
X898333Y-473667D01*
X899133Y-473400D01*
X899633Y-472867D01*
X900033Y-472200D01*
X900633Y-470067D01*
X901933Y-465667D01*
G01X898733D02*
X900633Y-470067D01*
G01X908333Y-473667D02*
X909333Y-472333D01*
X909833Y-471000D01*
Y-465667D01*
X909333Y-464333D01*
X908333Y-463000D01*
G01X649533Y-496500D02*
Y-488500D01*
X654133Y-496500D01*
Y-488500D01*
G01X657833Y-496500D02*
Y-488500D01*
X660233D01*
X661033Y-488900D01*
X661633Y-489833D01*
X661833Y-490900D01*
X661633Y-491967D01*
X661133Y-492767D01*
X660233Y-493167D01*
X657833D01*
G01X667833Y-488500D02*
Y-496500D01*
G01X665533Y-488500D02*
X670133D01*
G01X673733Y-496500D02*
Y-488500D01*
G01X677933D02*
Y-496500D01*
G01Y-492500D02*
X673733D01*
G01X689733Y-495434D02*
X690533Y-496100D01*
X691433Y-496500D01*
X692233D01*
X693033Y-496100D01*
X693633Y-495434D01*
X693933Y-494500D01*
X693733Y-493567D01*
X693233Y-492767D01*
X692333Y-492233D01*
X691133Y-491967D01*
X690433Y-491433D01*
X690133Y-490500D01*
X690333Y-489567D01*
X690833Y-488900D01*
X691533Y-488500D01*
X692233D01*
X692933Y-488767D01*
X693533Y-489433D01*
G01X699833Y-491167D02*
Y-496500D01*
G01Y-489033D02*
X699633Y-488900D01*
Y-488633D01*
X699833Y-488500D01*
X700033Y-488633D01*
Y-488900D01*
X699833Y-489033D01*
G01X706333Y-491167D02*
X709333D01*
X706333Y-496500D01*
X709333D01*
G01X714333Y-492900D02*
X717533D01*
X717233Y-491967D01*
X716733Y-491433D01*
X716033Y-491167D01*
X715333Y-491300D01*
X714733Y-491700D01*
X714333Y-492633D01*
X714133Y-493434D01*
Y-494233D01*
X714333Y-495033D01*
X714833Y-495833D01*
X715433Y-496367D01*
X716133Y-496500D01*
X716833Y-496233D01*
X717533Y-495434D01*
G01X729933Y-489833D02*
X730533Y-489033D01*
X731233Y-488633D01*
X732033Y-488500D01*
X733033Y-488767D01*
X733733Y-489433D01*
X733933Y-490233D01*
X733833Y-491034D01*
X733433Y-491700D01*
X731433Y-493033D01*
X730533Y-493967D01*
X729933Y-495300D01*
X729733Y-496500D01*
X733933D01*
G01X739833Y-496767D02*
X739633Y-496633D01*
Y-496367D01*
X739833Y-496233D01*
X740033Y-496367D01*
Y-496633D01*
X739833Y-496767D01*
G01X747833Y-496500D02*
Y-488500D01*
X746633Y-490100D01*
G01Y-496500D02*
X749033D01*
G01X755833D02*
X756533Y-496367D01*
X757333Y-495967D01*
X757833Y-495300D01*
X758033Y-494367D01*
X757833Y-493434D01*
X757233Y-492633D01*
X756333Y-492233D01*
X755333D01*
X754733Y-491967D01*
X754233Y-491300D01*
X754033Y-490367D01*
X754333Y-489433D01*
X755033Y-488767D01*
X755833Y-488500D01*
X756633Y-488767D01*
X757333Y-489433D01*
X757633Y-490367D01*
X757433Y-491300D01*
X756933Y-491967D01*
X756333Y-492233D01*
X755333D01*
X754433Y-492633D01*
X753833Y-493434D01*
X753633Y-494367D01*
X753833Y-495300D01*
X754333Y-495967D01*
X755133Y-496367D01*
X755833Y-496500D01*
G01X760833D02*
Y-491167D01*
G01Y-492633D02*
X761133Y-491967D01*
X761633Y-491433D01*
X762333Y-491167D01*
X763033Y-491433D01*
X763533Y-491967D01*
X763833Y-492633D01*
Y-496500D01*
G01Y-492633D02*
X764133Y-491967D01*
X764633Y-491433D01*
X765333Y-491167D01*
X766033Y-491433D01*
X766533Y-491967D01*
X766833Y-492767D01*
Y-496500D01*
G01X768833D02*
Y-491167D01*
G01Y-492633D02*
X769133Y-491967D01*
X769633Y-491433D01*
X770333Y-491167D01*
X771033Y-491433D01*
X771533Y-491967D01*
X771833Y-492633D01*
Y-496500D01*
G01Y-492633D02*
X772133Y-491967D01*
X772633Y-491433D01*
X773333Y-491167D01*
X774033Y-491433D01*
X774533Y-491967D01*
X774833Y-492767D01*
Y-496500D01*
G01X787333Y-499167D02*
X786333Y-497833D01*
X785833Y-496500D01*
Y-491167D01*
X786333Y-489833D01*
X787333Y-488500D01*
G01X795833Y-496500D02*
X795233Y-496367D01*
X794633Y-495833D01*
X794233Y-494900D01*
X794033Y-493833D01*
X794233Y-492767D01*
X794633Y-491833D01*
X795233Y-491300D01*
X795833Y-491167D01*
X796433Y-491300D01*
X797033Y-491833D01*
X797433Y-492767D01*
X797533Y-493833D01*
X797433Y-494900D01*
X797033Y-495833D01*
X796433Y-496367D01*
X795833Y-496500D01*
G01X802133D02*
Y-491167D01*
G01Y-492500D02*
X802533Y-491833D01*
X803133Y-491300D01*
X803933Y-491167D01*
X804633Y-491300D01*
X805233Y-491833D01*
X805533Y-492767D01*
Y-496500D01*
G01X818033D02*
Y-488500D01*
G01Y-492500D02*
X818533Y-491700D01*
X819133Y-491300D01*
X819733Y-491167D01*
X820633Y-491433D01*
X821233Y-491967D01*
X821633Y-492900D01*
Y-493967D01*
X821433Y-495033D01*
X821033Y-495833D01*
X820333Y-496367D01*
X819733Y-496500D01*
X819133Y-496367D01*
X818533Y-495967D01*
X818033Y-495300D01*
G01X826433Y-496500D02*
Y-491167D01*
G01Y-492233D02*
X826933Y-491700D01*
X827433Y-491300D01*
X828133Y-491167D01*
X828633Y-491300D01*
X829233Y-491700D01*
G01X834333Y-492900D02*
X837533D01*
X837233Y-491967D01*
X836733Y-491433D01*
X836033Y-491167D01*
X835333Y-491300D01*
X834733Y-491700D01*
X834333Y-492633D01*
X834133Y-493434D01*
Y-494233D01*
X834333Y-495033D01*
X834833Y-495833D01*
X835433Y-496367D01*
X836133Y-496500D01*
X836833Y-496233D01*
X837533Y-495434D01*
G01X845633Y-496500D02*
Y-491167D01*
G01Y-492100D02*
X845233Y-491567D01*
X844633Y-491300D01*
X843933Y-491167D01*
X843233Y-491433D01*
X842633Y-491967D01*
X842233Y-492767D01*
X842033Y-493833D01*
X842233Y-494900D01*
X842633Y-495700D01*
X843233Y-496233D01*
X843933Y-496500D01*
X844633Y-496367D01*
X845233Y-495967D01*
X845633Y-495434D01*
G01X850133Y-496500D02*
Y-488500D01*
G01X853333Y-491167D02*
X850133Y-494233D01*
G01X851433Y-493033D02*
X853533Y-496500D01*
G01X861633D02*
Y-491167D01*
G01Y-492100D02*
X861233Y-491567D01*
X860633Y-491300D01*
X859933Y-491167D01*
X859233Y-491433D01*
X858633Y-491967D01*
X858233Y-492767D01*
X858033Y-493833D01*
X858233Y-494900D01*
X858633Y-495700D01*
X859233Y-496233D01*
X859933Y-496500D01*
X860633Y-496367D01*
X861233Y-495967D01*
X861633Y-495434D01*
G01X865333Y-491167D02*
X866533Y-496500D01*
X867833Y-491167D01*
X869133Y-496500D01*
X870333Y-491167D01*
G01X877633Y-496500D02*
Y-491167D01*
G01Y-492100D02*
X877233Y-491567D01*
X876633Y-491300D01*
X875933Y-491167D01*
X875233Y-491433D01*
X874633Y-491967D01*
X874233Y-492767D01*
X874033Y-493833D01*
X874233Y-494900D01*
X874633Y-495700D01*
X875233Y-496233D01*
X875933Y-496500D01*
X876633Y-496367D01*
X877233Y-495967D01*
X877633Y-495434D01*
G01X881733Y-498900D02*
X882333Y-499167D01*
X883133Y-498900D01*
X883633Y-498367D01*
X884033Y-497700D01*
X884633Y-495567D01*
X885933Y-491167D01*
G01X882733D02*
X884633Y-495567D01*
G01X892333Y-499167D02*
X893333Y-497833D01*
X893833Y-496500D01*
Y-491167D01*
X893333Y-489833D01*
X892333Y-488500D01*
G01X649533Y-484500D02*
Y-476500D01*
X654133Y-484500D01*
Y-476500D01*
G01X657833Y-484500D02*
Y-476500D01*
X660233D01*
X661033Y-476900D01*
X661633Y-477833D01*
X661833Y-478900D01*
X661633Y-479967D01*
X661133Y-480767D01*
X660233Y-481167D01*
X657833D01*
G01X667833Y-476500D02*
Y-484500D01*
G01X665533Y-476500D02*
X670133D01*
G01X673733Y-484500D02*
Y-476500D01*
G01X677933D02*
Y-484500D01*
G01Y-480500D02*
X673733D01*
G01X689733Y-483434D02*
X690533Y-484100D01*
X691433Y-484500D01*
X692233D01*
X693033Y-484100D01*
X693633Y-483434D01*
X693933Y-482500D01*
X693733Y-481567D01*
X693233Y-480767D01*
X692333Y-480233D01*
X691133Y-479967D01*
X690433Y-479433D01*
X690133Y-478500D01*
X690333Y-477567D01*
X690833Y-476900D01*
X691533Y-476500D01*
X692233D01*
X692933Y-476767D01*
X693533Y-477433D01*
G01X699833Y-479167D02*
Y-484500D01*
G01Y-477033D02*
X699633Y-476900D01*
Y-476633D01*
X699833Y-476500D01*
X700033Y-476633D01*
Y-476900D01*
X699833Y-477033D01*
G01X706333Y-479167D02*
X709333D01*
X706333Y-484500D01*
X709333D01*
G01X714333Y-480900D02*
X717533D01*
X717233Y-479967D01*
X716733Y-479433D01*
X716033Y-479167D01*
X715333Y-479300D01*
X714733Y-479700D01*
X714333Y-480633D01*
X714133Y-481434D01*
Y-482233D01*
X714333Y-483033D01*
X714833Y-483833D01*
X715433Y-484367D01*
X716133Y-484500D01*
X716833Y-484233D01*
X717533Y-483434D01*
G01X729633Y-482900D02*
X730233Y-483833D01*
X731033Y-484367D01*
X731933Y-484500D01*
X732733Y-484367D01*
X733533Y-483700D01*
X734033Y-482900D01*
X734133Y-482100D01*
X733933Y-481167D01*
X733233Y-480500D01*
X732533Y-480233D01*
X731633D01*
G01X732533D02*
X733133Y-479833D01*
X733633Y-479167D01*
X733833Y-478367D01*
X733633Y-477567D01*
X733133Y-476900D01*
X732233Y-476500D01*
X731333Y-476633D01*
X730433Y-477167D01*
G01X739833Y-484767D02*
X739633Y-484633D01*
Y-484367D01*
X739833Y-484233D01*
X740033Y-484367D01*
Y-484633D01*
X739833Y-484767D01*
G01X745633Y-483300D02*
X746233Y-483967D01*
X746933Y-484367D01*
X747833Y-484500D01*
X748733Y-484233D01*
X749433Y-483700D01*
X749933Y-482767D01*
X750033Y-481700D01*
X749833Y-480633D01*
X749333Y-479967D01*
X748633Y-479433D01*
X747933Y-479300D01*
X747233Y-479433D01*
X746333Y-479967D01*
X746633Y-476500D01*
X749333D01*
G01X753633Y-483300D02*
X754233Y-483967D01*
X754933Y-484367D01*
X755833Y-484500D01*
X756733Y-484233D01*
X757433Y-483700D01*
X757933Y-482767D01*
X758033Y-481700D01*
X757833Y-480633D01*
X757333Y-479967D01*
X756633Y-479433D01*
X755933Y-479300D01*
X755233Y-479433D01*
X754333Y-479967D01*
X754633Y-476500D01*
X757333D01*
G01X760833Y-484500D02*
Y-479167D01*
G01Y-480633D02*
X761133Y-479967D01*
X761633Y-479433D01*
X762333Y-479167D01*
X763033Y-479433D01*
X763533Y-479967D01*
X763833Y-480633D01*
Y-484500D01*
G01Y-480633D02*
X764133Y-479967D01*
X764633Y-479433D01*
X765333Y-479167D01*
X766033Y-479433D01*
X766533Y-479967D01*
X766833Y-480767D01*
Y-484500D01*
G01X768833D02*
Y-479167D01*
G01Y-480633D02*
X769133Y-479967D01*
X769633Y-479433D01*
X770333Y-479167D01*
X771033Y-479433D01*
X771533Y-479967D01*
X771833Y-480633D01*
Y-484500D01*
G01Y-480633D02*
X772133Y-479967D01*
X772633Y-479433D01*
X773333Y-479167D01*
X774033Y-479433D01*
X774533Y-479967D01*
X774833Y-480767D01*
Y-484500D01*
G01X787333Y-487167D02*
X786333Y-485833D01*
X785833Y-484500D01*
Y-479167D01*
X786333Y-477833D01*
X787333Y-476500D01*
G01X795833Y-484500D02*
X795233Y-484367D01*
X794633Y-483833D01*
X794233Y-482900D01*
X794033Y-481833D01*
X794233Y-480767D01*
X794633Y-479833D01*
X795233Y-479300D01*
X795833Y-479167D01*
X796433Y-479300D01*
X797033Y-479833D01*
X797433Y-480767D01*
X797533Y-481833D01*
X797433Y-482900D01*
X797033Y-483833D01*
X796433Y-484367D01*
X795833Y-484500D01*
G01X802133D02*
Y-479167D01*
G01Y-480500D02*
X802533Y-479833D01*
X803133Y-479300D01*
X803933Y-479167D01*
X804633Y-479300D01*
X805233Y-479833D01*
X805533Y-480767D01*
Y-484500D01*
G01X818033D02*
Y-476500D01*
G01Y-480500D02*
X818533Y-479700D01*
X819133Y-479300D01*
X819733Y-479167D01*
X820633Y-479433D01*
X821233Y-479967D01*
X821633Y-480900D01*
Y-481967D01*
X821433Y-483033D01*
X821033Y-483833D01*
X820333Y-484367D01*
X819733Y-484500D01*
X819133Y-484367D01*
X818533Y-483967D01*
X818033Y-483300D01*
G01X826433Y-484500D02*
Y-479167D01*
G01Y-480233D02*
X826933Y-479700D01*
X827433Y-479300D01*
X828133Y-479167D01*
X828633Y-479300D01*
X829233Y-479700D01*
G01X834333Y-480900D02*
X837533D01*
X837233Y-479967D01*
X836733Y-479433D01*
X836033Y-479167D01*
X835333Y-479300D01*
X834733Y-479700D01*
X834333Y-480633D01*
X834133Y-481434D01*
Y-482233D01*
X834333Y-483033D01*
X834833Y-483833D01*
X835433Y-484367D01*
X836133Y-484500D01*
X836833Y-484233D01*
X837533Y-483434D01*
G01X845633Y-484500D02*
Y-479167D01*
G01Y-480100D02*
X845233Y-479567D01*
X844633Y-479300D01*
X843933Y-479167D01*
X843233Y-479433D01*
X842633Y-479967D01*
X842233Y-480767D01*
X842033Y-481833D01*
X842233Y-482900D01*
X842633Y-483700D01*
X843233Y-484233D01*
X843933Y-484500D01*
X844633Y-484367D01*
X845233Y-483967D01*
X845633Y-483434D01*
G01X850133Y-484500D02*
Y-476500D01*
G01X853333Y-479167D02*
X850133Y-482233D01*
G01X851433Y-481033D02*
X853533Y-484500D01*
G01X861633D02*
Y-479167D01*
G01Y-480100D02*
X861233Y-479567D01*
X860633Y-479300D01*
X859933Y-479167D01*
X859233Y-479433D01*
X858633Y-479967D01*
X858233Y-480767D01*
X858033Y-481833D01*
X858233Y-482900D01*
X858633Y-483700D01*
X859233Y-484233D01*
X859933Y-484500D01*
X860633Y-484367D01*
X861233Y-483967D01*
X861633Y-483434D01*
G01X865333Y-479167D02*
X866533Y-484500D01*
X867833Y-479167D01*
X869133Y-484500D01*
X870333Y-479167D01*
G01X877633Y-484500D02*
Y-479167D01*
G01Y-480100D02*
X877233Y-479567D01*
X876633Y-479300D01*
X875933Y-479167D01*
X875233Y-479433D01*
X874633Y-479967D01*
X874233Y-480767D01*
X874033Y-481833D01*
X874233Y-482900D01*
X874633Y-483700D01*
X875233Y-484233D01*
X875933Y-484500D01*
X876633Y-484367D01*
X877233Y-483967D01*
X877633Y-483434D01*
G01X881733Y-486900D02*
X882333Y-487167D01*
X883133Y-486900D01*
X883633Y-486367D01*
X884033Y-485700D01*
X884633Y-483567D01*
X885933Y-479167D01*
G01X882733D02*
X884633Y-483567D01*
G01X892333Y-487167D02*
X893333Y-485833D01*
X893833Y-484500D01*
Y-479167D01*
X893333Y-477833D01*
X892333Y-476500D01*
G01X648833Y-421000D02*
Y-413000D01*
X651233D01*
X652033Y-413400D01*
X652633Y-414333D01*
X652833Y-415400D01*
X652633Y-416467D01*
X652133Y-417267D01*
X651233Y-417667D01*
X648833D01*
G01X658833Y-421000D02*
Y-413000D01*
G01X665133Y-415667D02*
Y-419400D01*
X665533Y-420333D01*
X666133Y-420867D01*
X666833Y-421000D01*
X667533Y-420867D01*
X668133Y-420333D01*
X668533Y-419400D01*
G01Y-421000D02*
Y-415667D01*
G01X673433Y-423000D02*
X674133Y-423533D01*
X674933Y-423667D01*
X675633Y-423533D01*
X676233Y-422867D01*
X676633Y-421933D01*
Y-415667D01*
G01Y-416733D02*
X676233Y-416200D01*
X675633Y-415800D01*
X674933Y-415667D01*
X674133Y-415933D01*
X673633Y-416467D01*
X673233Y-417400D01*
X673033Y-418333D01*
X673133Y-419133D01*
X673533Y-420067D01*
X674133Y-420733D01*
X674933Y-421000D01*
X675533Y-420867D01*
X676233Y-420333D01*
X676633Y-419800D01*
G01X681433Y-423000D02*
X682133Y-423533D01*
X682933Y-423667D01*
X683633Y-423533D01*
X684233Y-422867D01*
X684633Y-421933D01*
Y-415667D01*
G01Y-416733D02*
X684233Y-416200D01*
X683633Y-415800D01*
X682933Y-415667D01*
X682133Y-415933D01*
X681633Y-416467D01*
X681233Y-417400D01*
X681033Y-418333D01*
X681133Y-419133D01*
X681533Y-420067D01*
X682133Y-420733D01*
X682933Y-421000D01*
X683533Y-420867D01*
X684233Y-420333D01*
X684633Y-419800D01*
G01X689333Y-417400D02*
X692533D01*
X692233Y-416467D01*
X691733Y-415933D01*
X691033Y-415667D01*
X690333Y-415800D01*
X689733Y-416200D01*
X689333Y-417133D01*
X689133Y-417934D01*
Y-418733D01*
X689333Y-419533D01*
X689833Y-420333D01*
X690433Y-420867D01*
X691133Y-421000D01*
X691833Y-420733D01*
X692533Y-419934D01*
G01X700633Y-413000D02*
Y-421000D01*
G01Y-419800D02*
X700233Y-420467D01*
X699633Y-420867D01*
X698933Y-421000D01*
X698133Y-420733D01*
X697533Y-420067D01*
X697133Y-419267D01*
X697033Y-418333D01*
X697133Y-417400D01*
X697533Y-416600D01*
X698133Y-415933D01*
X698933Y-415667D01*
X699633Y-415800D01*
X700133Y-416067D01*
X700633Y-416600D01*
G01X712833Y-421000D02*
Y-413000D01*
X715233D01*
X716033Y-413400D01*
X716633Y-414333D01*
X716833Y-415400D01*
X716633Y-416467D01*
X716133Y-417267D01*
X715233Y-417667D01*
X712833D01*
G01X722833Y-413000D02*
Y-421000D01*
G01X720533Y-413000D02*
X725133D01*
G01X728733Y-421000D02*
Y-413000D01*
G01X732933D02*
Y-421000D01*
G01Y-417000D02*
X728733D01*
G01X738333Y-423667D02*
X737333Y-422333D01*
X736833Y-421000D01*
Y-415667D01*
X737333Y-414333D01*
X738333Y-413000D01*
G01X745133Y-421000D02*
Y-413000D01*
G01Y-416867D02*
X745633Y-416200D01*
X746133Y-415800D01*
X746933Y-415667D01*
X747533Y-415800D01*
X748233Y-416333D01*
X748533Y-417133D01*
Y-421000D01*
G01X754833D02*
X754233Y-420867D01*
X753633Y-420333D01*
X753233Y-419400D01*
X753033Y-418333D01*
X753233Y-417267D01*
X753633Y-416333D01*
X754233Y-415800D01*
X754833Y-415667D01*
X755433Y-415800D01*
X756033Y-416333D01*
X756433Y-417267D01*
X756533Y-418333D01*
X756433Y-419400D01*
X756033Y-420333D01*
X755433Y-420867D01*
X754833Y-421000D01*
G01X762833D02*
Y-413000D01*
G01X769333Y-417400D02*
X772533D01*
X772233Y-416467D01*
X771733Y-415933D01*
X771033Y-415667D01*
X770333Y-415800D01*
X769733Y-416200D01*
X769333Y-417133D01*
X769133Y-417934D01*
Y-418733D01*
X769333Y-419533D01*
X769833Y-420333D01*
X770433Y-420867D01*
X771133Y-421000D01*
X771833Y-420733D01*
X772533Y-419934D01*
G01X785333Y-420067D02*
X785833Y-420600D01*
X786533Y-421000D01*
X787133D01*
X787733Y-420733D01*
X788133Y-420333D01*
X788333Y-419800D01*
X788233Y-419000D01*
X787833Y-418600D01*
X786033Y-417800D01*
X785633Y-416867D01*
X785833Y-416200D01*
X786233Y-415800D01*
X786833Y-415667D01*
X787433Y-415800D01*
X788033Y-416200D01*
G01X794833Y-415667D02*
Y-421000D01*
G01Y-413533D02*
X794633Y-413400D01*
Y-413133D01*
X794833Y-413000D01*
X795033Y-413133D01*
Y-413400D01*
X794833Y-413533D01*
G01X801333Y-415667D02*
X804333D01*
X801333Y-421000D01*
X804333D01*
G01X809333Y-417400D02*
X812533D01*
X812233Y-416467D01*
X811733Y-415933D01*
X811033Y-415667D01*
X810333Y-415800D01*
X809733Y-416200D01*
X809333Y-417133D01*
X809133Y-417934D01*
Y-418733D01*
X809333Y-419533D01*
X809833Y-420333D01*
X810433Y-420867D01*
X811133Y-421000D01*
X811833Y-420733D01*
X812533Y-419934D01*
G01X816833Y-421000D02*
X820833Y-418333D01*
X816833Y-415667D01*
G01X825533Y-419533D02*
X828133D01*
G01Y-417133D02*
X825533D01*
G01X834833Y-421000D02*
Y-413000D01*
X833633Y-414600D01*
G01Y-421000D02*
X836033D01*
G01X840933Y-417667D02*
X841633Y-416733D01*
X842233Y-416200D01*
X843033Y-415933D01*
X843733Y-416200D01*
X844233Y-416733D01*
X844633Y-417533D01*
X844733Y-418467D01*
X844633Y-419267D01*
X844233Y-420067D01*
X843633Y-420733D01*
X842933Y-421000D01*
X842133Y-420733D01*
X841433Y-419934D01*
X841033Y-418733D01*
X840933Y-417400D01*
X841133Y-415667D01*
X841433Y-414733D01*
X841933Y-413800D01*
X842633Y-413133D01*
X843333Y-413000D01*
X844033Y-413267D01*
X844533Y-413933D01*
G01X855833Y-421000D02*
Y-415667D01*
G01Y-417133D02*
X856133Y-416467D01*
X856633Y-415933D01*
X857333Y-415667D01*
X858033Y-415933D01*
X858533Y-416467D01*
X858833Y-417133D01*
Y-421000D01*
G01Y-417133D02*
X859133Y-416467D01*
X859633Y-415933D01*
X860333Y-415667D01*
X861033Y-415933D01*
X861533Y-416467D01*
X861833Y-417267D01*
Y-421000D01*
G01X866833Y-415667D02*
Y-421000D01*
G01Y-413533D02*
X866633Y-413400D01*
Y-413133D01*
X866833Y-413000D01*
X867033Y-413133D01*
Y-413400D01*
X866833Y-413533D01*
G01X874833Y-421000D02*
Y-413000D01*
G01X883333Y-423667D02*
X884333Y-422333D01*
X884833Y-421000D01*
Y-415667D01*
X884333Y-414333D01*
X883333Y-413000D01*
G01X648833Y-408500D02*
Y-400500D01*
X651233D01*
X652033Y-400900D01*
X652633Y-401833D01*
X652833Y-402900D01*
X652633Y-403967D01*
X652133Y-404767D01*
X651233Y-405167D01*
X648833D01*
G01X658833Y-408500D02*
Y-400500D01*
G01X665133Y-403167D02*
Y-406900D01*
X665533Y-407833D01*
X666133Y-408367D01*
X666833Y-408500D01*
X667533Y-408367D01*
X668133Y-407833D01*
X668533Y-406900D01*
G01Y-408500D02*
Y-403167D01*
G01X673433Y-410500D02*
X674133Y-411033D01*
X674933Y-411167D01*
X675633Y-411033D01*
X676233Y-410367D01*
X676633Y-409433D01*
Y-403167D01*
G01Y-404233D02*
X676233Y-403700D01*
X675633Y-403300D01*
X674933Y-403167D01*
X674133Y-403433D01*
X673633Y-403967D01*
X673233Y-404900D01*
X673033Y-405833D01*
X673133Y-406633D01*
X673533Y-407567D01*
X674133Y-408233D01*
X674933Y-408500D01*
X675533Y-408367D01*
X676233Y-407833D01*
X676633Y-407300D01*
G01X681433Y-410500D02*
X682133Y-411033D01*
X682933Y-411167D01*
X683633Y-411033D01*
X684233Y-410367D01*
X684633Y-409433D01*
Y-403167D01*
G01Y-404233D02*
X684233Y-403700D01*
X683633Y-403300D01*
X682933Y-403167D01*
X682133Y-403433D01*
X681633Y-403967D01*
X681233Y-404900D01*
X681033Y-405833D01*
X681133Y-406633D01*
X681533Y-407567D01*
X682133Y-408233D01*
X682933Y-408500D01*
X683533Y-408367D01*
X684233Y-407833D01*
X684633Y-407300D01*
G01X689333Y-404900D02*
X692533D01*
X692233Y-403967D01*
X691733Y-403433D01*
X691033Y-403167D01*
X690333Y-403300D01*
X689733Y-403700D01*
X689333Y-404633D01*
X689133Y-405434D01*
Y-406233D01*
X689333Y-407033D01*
X689833Y-407833D01*
X690433Y-408367D01*
X691133Y-408500D01*
X691833Y-408233D01*
X692533Y-407434D01*
G01X700633Y-400500D02*
Y-408500D01*
G01Y-407300D02*
X700233Y-407967D01*
X699633Y-408367D01*
X698933Y-408500D01*
X698133Y-408233D01*
X697533Y-407567D01*
X697133Y-406767D01*
X697033Y-405833D01*
X697133Y-404900D01*
X697533Y-404100D01*
X698133Y-403433D01*
X698933Y-403167D01*
X699633Y-403300D01*
X700133Y-403567D01*
X700633Y-404100D01*
G01X712333Y-400500D02*
X714833Y-408500D01*
X717333Y-400500D01*
G01X722833Y-403167D02*
Y-408500D01*
G01Y-401033D02*
X722633Y-400900D01*
Y-400633D01*
X722833Y-400500D01*
X723033Y-400633D01*
Y-400900D01*
X722833Y-401033D01*
G01X732633Y-408500D02*
Y-403167D01*
G01Y-404100D02*
X732233Y-403567D01*
X731633Y-403300D01*
X730933Y-403167D01*
X730233Y-403433D01*
X729633Y-403967D01*
X729233Y-404767D01*
X729033Y-405833D01*
X729233Y-406900D01*
X729633Y-407700D01*
X730233Y-408233D01*
X730933Y-408500D01*
X731633Y-408367D01*
X732233Y-407967D01*
X732633Y-407434D01*
G01X738333Y-411167D02*
X737333Y-409833D01*
X736833Y-408500D01*
Y-403167D01*
X737333Y-401833D01*
X738333Y-400500D01*
G01X745133Y-408500D02*
Y-400500D01*
G01Y-404367D02*
X745633Y-403700D01*
X746133Y-403300D01*
X746933Y-403167D01*
X747533Y-403300D01*
X748233Y-403833D01*
X748533Y-404633D01*
Y-408500D01*
G01X754833D02*
X754233Y-408367D01*
X753633Y-407833D01*
X753233Y-406900D01*
X753033Y-405833D01*
X753233Y-404767D01*
X753633Y-403833D01*
X754233Y-403300D01*
X754833Y-403167D01*
X755433Y-403300D01*
X756033Y-403833D01*
X756433Y-404767D01*
X756533Y-405833D01*
X756433Y-406900D01*
X756033Y-407833D01*
X755433Y-408367D01*
X754833Y-408500D01*
G01X762833D02*
Y-400500D01*
G01X769333Y-404900D02*
X772533D01*
X772233Y-403967D01*
X771733Y-403433D01*
X771033Y-403167D01*
X770333Y-403300D01*
X769733Y-403700D01*
X769333Y-404633D01*
X769133Y-405434D01*
Y-406233D01*
X769333Y-407033D01*
X769833Y-407833D01*
X770433Y-408367D01*
X771133Y-408500D01*
X771833Y-408233D01*
X772533Y-407434D01*
G01X785333Y-407567D02*
X785833Y-408100D01*
X786533Y-408500D01*
X787133D01*
X787733Y-408233D01*
X788133Y-407833D01*
X788333Y-407300D01*
X788233Y-406500D01*
X787833Y-406100D01*
X786033Y-405300D01*
X785633Y-404367D01*
X785833Y-403700D01*
X786233Y-403300D01*
X786833Y-403167D01*
X787433Y-403300D01*
X788033Y-403700D01*
G01X794833Y-403167D02*
Y-408500D01*
G01Y-401033D02*
X794633Y-400900D01*
Y-400633D01*
X794833Y-400500D01*
X795033Y-400633D01*
Y-400900D01*
X794833Y-401033D01*
G01X801333Y-403167D02*
X804333D01*
X801333Y-408500D01*
X804333D01*
G01X809333Y-404900D02*
X812533D01*
X812233Y-403967D01*
X811733Y-403433D01*
X811033Y-403167D01*
X810333Y-403300D01*
X809733Y-403700D01*
X809333Y-404633D01*
X809133Y-405434D01*
Y-406233D01*
X809333Y-407033D01*
X809833Y-407833D01*
X810433Y-408367D01*
X811133Y-408500D01*
X811833Y-408233D01*
X812533Y-407434D01*
G01X820833Y-408500D02*
X816833Y-405833D01*
X820833Y-403167D01*
G01X826833Y-408500D02*
Y-400500D01*
X825633Y-402100D01*
G01Y-408500D02*
X828033D01*
G01X832933Y-405167D02*
X833633Y-404233D01*
X834233Y-403700D01*
X835033Y-403433D01*
X835733Y-403700D01*
X836233Y-404233D01*
X836633Y-405033D01*
X836733Y-405967D01*
X836633Y-406767D01*
X836233Y-407567D01*
X835633Y-408233D01*
X834933Y-408500D01*
X834133Y-408233D01*
X833433Y-407434D01*
X833033Y-406233D01*
X832933Y-404900D01*
X833133Y-403167D01*
X833433Y-402233D01*
X833933Y-401300D01*
X834633Y-400633D01*
X835333Y-400500D01*
X836033Y-400767D01*
X836533Y-401433D01*
G01X847833Y-408500D02*
Y-403167D01*
G01Y-404633D02*
X848133Y-403967D01*
X848633Y-403433D01*
X849333Y-403167D01*
X850033Y-403433D01*
X850533Y-403967D01*
X850833Y-404633D01*
Y-408500D01*
G01Y-404633D02*
X851133Y-403967D01*
X851633Y-403433D01*
X852333Y-403167D01*
X853033Y-403433D01*
X853533Y-403967D01*
X853833Y-404767D01*
Y-408500D01*
G01X858833Y-403167D02*
Y-408500D01*
G01Y-401033D02*
X858633Y-400900D01*
Y-400633D01*
X858833Y-400500D01*
X859033Y-400633D01*
Y-400900D01*
X858833Y-401033D01*
G01X866833Y-408500D02*
Y-400500D01*
G01X875333Y-411167D02*
X876333Y-409833D01*
X876833Y-408500D01*
Y-403167D01*
X876333Y-401833D01*
X875333Y-400500D01*
G01X648833Y-425500D02*
Y-433500D01*
X652833D01*
G01X660633D02*
Y-428167D01*
G01Y-429100D02*
X660233Y-428567D01*
X659633Y-428300D01*
X658933Y-428167D01*
X658233Y-428433D01*
X657633Y-428967D01*
X657233Y-429767D01*
X657033Y-430833D01*
X657233Y-431900D01*
X657633Y-432700D01*
X658233Y-433233D01*
X658933Y-433500D01*
X659633Y-433367D01*
X660233Y-432967D01*
X660633Y-432434D01*
G01X665333Y-432567D02*
X665833Y-433100D01*
X666533Y-433500D01*
X667133D01*
X667733Y-433233D01*
X668133Y-432833D01*
X668333Y-432300D01*
X668233Y-431500D01*
X667833Y-431100D01*
X666033Y-430300D01*
X665633Y-429367D01*
X665833Y-428700D01*
X666233Y-428300D01*
X666833Y-428167D01*
X667433Y-428300D01*
X668033Y-428700D01*
G01X673333Y-429900D02*
X676533D01*
X676233Y-428967D01*
X675733Y-428433D01*
X675033Y-428167D01*
X674333Y-428300D01*
X673733Y-428700D01*
X673333Y-429633D01*
X673133Y-430434D01*
Y-431233D01*
X673333Y-432033D01*
X673833Y-432833D01*
X674433Y-433367D01*
X675133Y-433500D01*
X675833Y-433233D01*
X676533Y-432434D01*
G01X681433Y-433500D02*
Y-428167D01*
G01Y-429233D02*
X681933Y-428700D01*
X682433Y-428300D01*
X683133Y-428167D01*
X683633Y-428300D01*
X684233Y-428700D01*
G01X697033Y-428167D02*
X698833Y-433500D01*
X700633Y-428167D01*
G01X706833D02*
Y-433500D01*
G01Y-426033D02*
X706633Y-425900D01*
Y-425633D01*
X706833Y-425500D01*
X707033Y-425633D01*
Y-425900D01*
X706833Y-426033D01*
G01X716633Y-433500D02*
Y-428167D01*
G01Y-429100D02*
X716233Y-428567D01*
X715633Y-428300D01*
X714933Y-428167D01*
X714233Y-428433D01*
X713633Y-428967D01*
X713233Y-429767D01*
X713033Y-430833D01*
X713233Y-431900D01*
X713633Y-432700D01*
X714233Y-433233D01*
X714933Y-433500D01*
X715633Y-433367D01*
X716233Y-432967D01*
X716633Y-432434D01*
G01X729133Y-433500D02*
Y-425500D01*
G01Y-429367D02*
X729633Y-428700D01*
X730133Y-428300D01*
X730933Y-428167D01*
X731533Y-428300D01*
X732233Y-428833D01*
X732533Y-429633D01*
Y-433500D01*
G01X738833D02*
X738233Y-433367D01*
X737633Y-432833D01*
X737233Y-431900D01*
X737033Y-430833D01*
X737233Y-429767D01*
X737633Y-428833D01*
X738233Y-428300D01*
X738833Y-428167D01*
X739433Y-428300D01*
X740033Y-428833D01*
X740433Y-429767D01*
X740533Y-430833D01*
X740433Y-431900D01*
X740033Y-432833D01*
X739433Y-433367D01*
X738833Y-433500D01*
G01X746833D02*
Y-425500D01*
G01X753333Y-429900D02*
X756533D01*
X756233Y-428967D01*
X755733Y-428433D01*
X755033Y-428167D01*
X754333Y-428300D01*
X753733Y-428700D01*
X753333Y-429633D01*
X753133Y-430434D01*
Y-431233D01*
X753333Y-432033D01*
X753833Y-432833D01*
X754433Y-433367D01*
X755133Y-433500D01*
X755833Y-433233D01*
X756533Y-432434D01*
G01X770333Y-436167D02*
X769333Y-434833D01*
X768833Y-433500D01*
Y-428167D01*
X769333Y-426833D01*
X770333Y-425500D01*
G01X777033Y-433500D02*
Y-425500D01*
G01Y-429500D02*
X777533Y-428700D01*
X778133Y-428300D01*
X778733Y-428167D01*
X779633Y-428433D01*
X780233Y-428967D01*
X780633Y-429900D01*
Y-430967D01*
X780433Y-432033D01*
X780033Y-432833D01*
X779333Y-433367D01*
X778733Y-433500D01*
X778133Y-433367D01*
X777533Y-432967D01*
X777033Y-432300D01*
G01X785333Y-429900D02*
X788533D01*
X788233Y-428967D01*
X787733Y-428433D01*
X787033Y-428167D01*
X786333Y-428300D01*
X785733Y-428700D01*
X785333Y-429633D01*
X785133Y-430434D01*
Y-431233D01*
X785333Y-432033D01*
X785833Y-432833D01*
X786433Y-433367D01*
X787133Y-433500D01*
X787833Y-433233D01*
X788533Y-432434D01*
G01X794233Y-433500D02*
Y-426700D01*
X794433Y-426033D01*
X794833Y-425633D01*
X795433Y-425500D01*
X796033Y-425767D01*
X796333Y-426433D01*
G01X795133Y-428700D02*
X793133D01*
G01X802833Y-433500D02*
X802233Y-433367D01*
X801633Y-432833D01*
X801233Y-431900D01*
X801033Y-430833D01*
X801233Y-429767D01*
X801633Y-428833D01*
X802233Y-428300D01*
X802833Y-428167D01*
X803433Y-428300D01*
X804033Y-428833D01*
X804433Y-429767D01*
X804533Y-430833D01*
X804433Y-431900D01*
X804033Y-432833D01*
X803433Y-433367D01*
X802833Y-433500D01*
G01X809433D02*
Y-428167D01*
G01Y-429233D02*
X809933Y-428700D01*
X810433Y-428300D01*
X811133Y-428167D01*
X811633Y-428300D01*
X812233Y-428700D01*
G01X817333Y-429900D02*
X820533D01*
X820233Y-428967D01*
X819733Y-428433D01*
X819033Y-428167D01*
X818333Y-428300D01*
X817733Y-428700D01*
X817333Y-429633D01*
X817133Y-430434D01*
Y-431233D01*
X817333Y-432033D01*
X817833Y-432833D01*
X818433Y-433367D01*
X819133Y-433500D01*
X819833Y-433233D01*
X820533Y-432434D01*
G01X834833Y-425500D02*
Y-433500D01*
G01X833433Y-428167D02*
X836233D01*
G01X841133Y-433500D02*
Y-425500D01*
G01Y-429367D02*
X841633Y-428700D01*
X842133Y-428300D01*
X842933Y-428167D01*
X843533Y-428300D01*
X844233Y-428833D01*
X844533Y-429633D01*
Y-433500D01*
G01X849333Y-429900D02*
X852533D01*
X852233Y-428967D01*
X851733Y-428433D01*
X851033Y-428167D01*
X850333Y-428300D01*
X849733Y-428700D01*
X849333Y-429633D01*
X849133Y-430434D01*
Y-431233D01*
X849333Y-432033D01*
X849833Y-432833D01*
X850433Y-433367D01*
X851133Y-433500D01*
X851833Y-433233D01*
X852533Y-432434D01*
G01X868433Y-428833D02*
X867733Y-428300D01*
X867133Y-428167D01*
X866333Y-428433D01*
X865733Y-428967D01*
X865333Y-429900D01*
X865233Y-430833D01*
X865333Y-431767D01*
X865733Y-432567D01*
X866333Y-433233D01*
X867133Y-433500D01*
X867833Y-433233D01*
X868433Y-432700D01*
G01X874833Y-433500D02*
X874233Y-433367D01*
X873633Y-432833D01*
X873233Y-431900D01*
X873033Y-430833D01*
X873233Y-429767D01*
X873633Y-428833D01*
X874233Y-428300D01*
X874833Y-428167D01*
X875433Y-428300D01*
X876033Y-428833D01*
X876433Y-429767D01*
X876533Y-430833D01*
X876433Y-431900D01*
X876033Y-432833D01*
X875433Y-433367D01*
X874833Y-433500D01*
G01X881033Y-436167D02*
Y-428167D01*
G01Y-429367D02*
X881533Y-428700D01*
X882033Y-428300D01*
X882833Y-428167D01*
X883533Y-428300D01*
X884233Y-428967D01*
X884533Y-429900D01*
X884633Y-430833D01*
X884533Y-431767D01*
X884233Y-432700D01*
X883633Y-433233D01*
X882833Y-433500D01*
X882133Y-433367D01*
X881433Y-432967D01*
X881033Y-432434D01*
G01X889033Y-436167D02*
Y-428167D01*
G01Y-429367D02*
X889533Y-428700D01*
X890033Y-428300D01*
X890833Y-428167D01*
X891533Y-428300D01*
X892233Y-428967D01*
X892533Y-429900D01*
X892633Y-430833D01*
X892533Y-431767D01*
X892233Y-432700D01*
X891633Y-433233D01*
X890833Y-433500D01*
X890133Y-433367D01*
X889433Y-432967D01*
X889033Y-432434D01*
G01X897333Y-429900D02*
X900533D01*
X900233Y-428967D01*
X899733Y-428433D01*
X899033Y-428167D01*
X898333Y-428300D01*
X897733Y-428700D01*
X897333Y-429633D01*
X897133Y-430434D01*
Y-431233D01*
X897333Y-432033D01*
X897833Y-432833D01*
X898433Y-433367D01*
X899133Y-433500D01*
X899833Y-433233D01*
X900533Y-432434D01*
G01X905433Y-433500D02*
Y-428167D01*
G01Y-429233D02*
X905933Y-428700D01*
X906433Y-428300D01*
X907133Y-428167D01*
X907633Y-428300D01*
X908233Y-428700D01*
G01X921033Y-436167D02*
Y-428167D01*
G01Y-429367D02*
X921533Y-428700D01*
X922033Y-428300D01*
X922833Y-428167D01*
X923533Y-428300D01*
X924233Y-428967D01*
X924533Y-429900D01*
X924633Y-430833D01*
X924533Y-431767D01*
X924233Y-432700D01*
X923633Y-433233D01*
X922833Y-433500D01*
X922133Y-433367D01*
X921433Y-432967D01*
X921033Y-432434D01*
G01X930833Y-433500D02*
Y-425500D01*
G01X940633Y-433500D02*
Y-428167D01*
G01Y-429100D02*
X940233Y-428567D01*
X939633Y-428300D01*
X938933Y-428167D01*
X938233Y-428433D01*
X937633Y-428967D01*
X937233Y-429767D01*
X937033Y-430833D01*
X937233Y-431900D01*
X937633Y-432700D01*
X938233Y-433233D01*
X938933Y-433500D01*
X939633Y-433367D01*
X940233Y-432967D01*
X940633Y-432434D01*
G01X946833Y-425500D02*
Y-433500D01*
G01X945433Y-428167D02*
X948233D01*
G01X954833D02*
Y-433500D01*
G01Y-426033D02*
X954633Y-425900D01*
Y-425633D01*
X954833Y-425500D01*
X955033Y-425633D01*
Y-425900D01*
X954833Y-426033D01*
G01X961133Y-433500D02*
Y-428167D01*
G01Y-429500D02*
X961533Y-428833D01*
X962133Y-428300D01*
X962933Y-428167D01*
X963633Y-428300D01*
X964233Y-428833D01*
X964533Y-429767D01*
Y-433500D01*
G01X969433Y-435500D02*
X970133Y-436033D01*
X970933Y-436167D01*
X971633Y-436033D01*
X972233Y-435367D01*
X972633Y-434433D01*
Y-428167D01*
G01Y-429233D02*
X972233Y-428700D01*
X971633Y-428300D01*
X970933Y-428167D01*
X970133Y-428433D01*
X969633Y-428967D01*
X969233Y-429900D01*
X969033Y-430833D01*
X969133Y-431633D01*
X969533Y-432567D01*
X970133Y-433233D01*
X970933Y-433500D01*
X971533Y-433367D01*
X972233Y-432833D01*
X972633Y-432300D01*
G01X979333Y-436167D02*
X980333Y-434833D01*
X980833Y-433500D01*
Y-428167D01*
X980333Y-426833D01*
X979333Y-425500D01*
G01X601733Y-335567D02*
X606133Y-329700D01*
G01X603933Y-328633D02*
Y-336633D01*
G01X606133Y-335567D02*
X601733Y-329700D01*
G01X600933Y-332633D02*
X606933D01*
G01X609733Y-335567D02*
X614133Y-329700D01*
G01X611933Y-328633D02*
Y-336633D01*
G01X614133Y-335567D02*
X609733Y-329700D01*
G01X608933Y-332633D02*
X614933D01*
G01X617733Y-335567D02*
X622133Y-329700D01*
G01X619933Y-328633D02*
Y-336633D01*
G01X622133Y-335567D02*
X617733Y-329700D01*
G01X616933Y-332633D02*
X622933D01*
G01X625733Y-335567D02*
X630133Y-329700D01*
G01X627933Y-328633D02*
Y-336633D01*
G01X630133Y-335567D02*
X625733Y-329700D01*
G01X624933Y-332633D02*
X630933D01*
G01X635933Y-335567D02*
X635733Y-335433D01*
Y-335167D01*
X635933Y-335033D01*
X636133Y-335167D01*
Y-335433D01*
X635933Y-335567D01*
G01Y-331967D02*
X635733Y-331833D01*
Y-331567D01*
X635933Y-331433D01*
X636133Y-331567D01*
Y-331833D01*
X635933Y-331967D01*
G01X650733Y-327300D02*
X653133D01*
G01X651933D02*
Y-335300D01*
G01X650733D02*
X653133D01*
G01X658533Y-337300D02*
X659233Y-337833D01*
X660033Y-337967D01*
X660733Y-337833D01*
X661333Y-337167D01*
X661733Y-336233D01*
Y-329967D01*
G01Y-331033D02*
X661333Y-330500D01*
X660733Y-330100D01*
X660033Y-329967D01*
X659233Y-330233D01*
X658733Y-330767D01*
X658333Y-331700D01*
X658133Y-332633D01*
X658233Y-333433D01*
X658633Y-334367D01*
X659233Y-335033D01*
X660033Y-335300D01*
X660633Y-335167D01*
X661333Y-334633D01*
X661733Y-334100D01*
G01X666233Y-335300D02*
Y-329967D01*
G01Y-331300D02*
X666633Y-330633D01*
X667233Y-330100D01*
X668033Y-329967D01*
X668733Y-330100D01*
X669333Y-330633D01*
X669633Y-331567D01*
Y-335300D01*
G01X675933D02*
X675333Y-335167D01*
X674733Y-334633D01*
X674333Y-333700D01*
X674133Y-332633D01*
X674333Y-331567D01*
X674733Y-330633D01*
X675333Y-330100D01*
X675933Y-329967D01*
X676533Y-330100D01*
X677133Y-330633D01*
X677533Y-331567D01*
X677633Y-332633D01*
X677533Y-333700D01*
X677133Y-334633D01*
X676533Y-335167D01*
X675933Y-335300D01*
G01X682533D02*
Y-329967D01*
G01Y-331033D02*
X683033Y-330500D01*
X683533Y-330100D01*
X684233Y-329967D01*
X684733Y-330100D01*
X685333Y-330500D01*
G01X690433Y-331700D02*
X693633D01*
X693333Y-330767D01*
X692833Y-330233D01*
X692133Y-329967D01*
X691433Y-330100D01*
X690833Y-330500D01*
X690433Y-331433D01*
X690233Y-332234D01*
Y-333033D01*
X690433Y-333833D01*
X690933Y-334633D01*
X691533Y-335167D01*
X692233Y-335300D01*
X692933Y-335033D01*
X693633Y-334234D01*
G01X707933Y-335300D02*
Y-327300D01*
X706733Y-328900D01*
G01Y-335300D02*
X709133D01*
G01X720933D02*
Y-329967D01*
G01Y-331433D02*
X721233Y-330767D01*
X721733Y-330233D01*
X722433Y-329967D01*
X723133Y-330233D01*
X723633Y-330767D01*
X723933Y-331433D01*
Y-335300D01*
G01Y-331433D02*
X724233Y-330767D01*
X724733Y-330233D01*
X725433Y-329967D01*
X726133Y-330233D01*
X726633Y-330767D01*
X726933Y-331567D01*
Y-335300D01*
G01X731933Y-329967D02*
Y-335300D01*
G01Y-327833D02*
X731733Y-327700D01*
Y-327433D01*
X731933Y-327300D01*
X732133Y-327433D01*
Y-327700D01*
X731933Y-327833D01*
G01X739933Y-335300D02*
Y-327300D01*
G01X753733Y-335300D02*
Y-327300D01*
X755733D01*
X756533Y-327700D01*
X757133Y-328233D01*
X757633Y-329033D01*
X758033Y-329967D01*
X758133Y-331300D01*
X758033Y-332633D01*
X757633Y-333567D01*
X757133Y-334367D01*
X756533Y-334900D01*
X755733Y-335300D01*
X753733D01*
G01X762633Y-332633D02*
X765233D01*
G01X774133Y-327967D02*
X773533Y-327567D01*
X772833Y-327300D01*
X772033D01*
X771133Y-327700D01*
X770433Y-328367D01*
X769933Y-329167D01*
X769533Y-330500D01*
X769433Y-331700D01*
X769633Y-332900D01*
X769933Y-333700D01*
X770533Y-334500D01*
X771233Y-335033D01*
X771933Y-335300D01*
X772633D01*
X773333Y-335033D01*
X773933Y-334633D01*
X774433Y-334100D01*
G01X779933Y-335300D02*
X779133Y-335167D01*
X778433Y-334633D01*
X777833Y-333833D01*
X777433Y-332900D01*
X777233Y-331833D01*
Y-330767D01*
X777433Y-329700D01*
X777833Y-328767D01*
X778433Y-327967D01*
X779133Y-327433D01*
X779933Y-327300D01*
X780733Y-327433D01*
X781433Y-327967D01*
X782033Y-328767D01*
X782433Y-329700D01*
X782633Y-330767D01*
Y-331833D01*
X782433Y-332900D01*
X782033Y-333833D01*
X781433Y-334633D01*
X780733Y-335167D01*
X779933Y-335300D01*
G01X785733D02*
Y-327300D01*
X787733D01*
X788533Y-327700D01*
X789133Y-328233D01*
X789633Y-329033D01*
X790033Y-329967D01*
X790133Y-331300D01*
X790033Y-332633D01*
X789633Y-333567D01*
X789133Y-334367D01*
X788533Y-334900D01*
X787733Y-335300D01*
X785733D01*
G01X797933D02*
X793933D01*
Y-327300D01*
X797933D01*
G01X796333Y-331167D02*
X793933D01*
G01X606033Y-290400D02*
Y-282400D01*
X610633Y-290400D01*
Y-282400D01*
G01X616333Y-290400D02*
X615733Y-290267D01*
X615133Y-289733D01*
X614733Y-288800D01*
X614533Y-287733D01*
X614733Y-286667D01*
X615133Y-285733D01*
X615733Y-285200D01*
X616333Y-285067D01*
X616933Y-285200D01*
X617533Y-285733D01*
X617933Y-286667D01*
X618033Y-287733D01*
X617933Y-288800D01*
X617533Y-289733D01*
X616933Y-290267D01*
X616333Y-290400D01*
G01X624333Y-282400D02*
Y-290400D01*
G01X622933Y-285067D02*
X625733D01*
G01X630833Y-286800D02*
X634033D01*
X633733Y-285867D01*
X633233Y-285333D01*
X632533Y-285067D01*
X631833Y-285200D01*
X631233Y-285600D01*
X630833Y-286533D01*
X630633Y-287334D01*
Y-288133D01*
X630833Y-288933D01*
X631333Y-289733D01*
X631933Y-290267D01*
X632633Y-290400D01*
X633333Y-290133D01*
X634033Y-289334D01*
G01X638833Y-289467D02*
X639333Y-290000D01*
X640033Y-290400D01*
X640633D01*
X641233Y-290133D01*
X641633Y-289733D01*
X641833Y-289200D01*
X641733Y-288400D01*
X641333Y-288000D01*
X639533Y-287200D01*
X639133Y-286267D01*
X639333Y-285600D01*
X639733Y-285200D01*
X640333Y-285067D01*
X640933Y-285200D01*
X641533Y-285600D01*
G01X648333Y-290667D02*
X648133Y-290533D01*
Y-290267D01*
X648333Y-290133D01*
X648533Y-290267D01*
Y-290533D01*
X648333Y-290667D01*
G01Y-287067D02*
X648133Y-286933D01*
Y-286667D01*
X648333Y-286533D01*
X648533Y-286667D01*
Y-286933D01*
X648333Y-287067D01*
G01X610233Y-124900D02*
X606233D01*
Y-116900D01*
X610233D01*
G01X608633Y-120767D02*
X606233D01*
G01X614133Y-124900D02*
X618333Y-116900D01*
G01X614133D02*
X618333Y-124900D01*
G01X624233Y-125167D02*
X624033Y-125033D01*
Y-124767D01*
X624233Y-124633D01*
X624433Y-124767D01*
Y-125033D01*
X624233Y-125167D01*
G01X646133Y-124900D02*
Y-116900D01*
G01X650333D02*
Y-124900D01*
G01Y-120900D02*
X646133D01*
G01X654233Y-124900D02*
Y-116900D01*
X656733D01*
X657533Y-117300D01*
X658033Y-117833D01*
X658233Y-118900D01*
X658033Y-119967D01*
X657433Y-120633D01*
X656733Y-121033D01*
X654233D01*
G01X656733D02*
X658233Y-124900D01*
G01X666233D02*
X662233D01*
Y-116900D01*
X666233D01*
G01X664633Y-120767D02*
X662233D01*
G01X673433Y-124900D02*
Y-116900D01*
X669733Y-122633D01*
X674733D01*
G01X678033Y-123700D02*
X678633Y-124367D01*
X679333Y-124767D01*
X680233Y-124900D01*
X681133Y-124633D01*
X681833Y-124100D01*
X682333Y-123167D01*
X682433Y-122100D01*
X682233Y-121033D01*
X681733Y-120367D01*
X681033Y-119833D01*
X680333Y-119700D01*
X679633Y-119833D01*
X678733Y-120367D01*
X679033Y-116900D01*
X681733D01*
G01X686133Y-124900D02*
X690333Y-116900D01*
G01X686133D02*
X690333Y-124900D01*
G01X694533Y-123967D02*
X695233Y-124633D01*
X696033Y-124900D01*
X696833Y-124633D01*
X697533Y-123834D01*
X698033Y-122633D01*
X698233Y-121433D01*
Y-119967D01*
X698033Y-118767D01*
X697533Y-117700D01*
X696933Y-117167D01*
X696233Y-116900D01*
X695433Y-117167D01*
X694833Y-117700D01*
X694433Y-118500D01*
X694233Y-119567D01*
X694433Y-120500D01*
X694933Y-121433D01*
X695533Y-121967D01*
X696233Y-122100D01*
X697033Y-121834D01*
X697633Y-121167D01*
X698233Y-119967D01*
G01X702333Y-121567D02*
X703033Y-120633D01*
X703633Y-120100D01*
X704433Y-119833D01*
X705133Y-120100D01*
X705633Y-120633D01*
X706033Y-121433D01*
X706133Y-122367D01*
X706033Y-123167D01*
X705633Y-123967D01*
X705033Y-124633D01*
X704333Y-124900D01*
X703533Y-124633D01*
X702833Y-123834D01*
X702433Y-122633D01*
X702333Y-121300D01*
X702533Y-119567D01*
X702833Y-118633D01*
X703333Y-117700D01*
X704033Y-117033D01*
X704733Y-116900D01*
X705433Y-117167D01*
X705933Y-117833D01*
G01X711733Y-127567D02*
X710733Y-126233D01*
X710233Y-124900D01*
Y-119567D01*
X710733Y-118233D01*
X711733Y-116900D01*
G01X718033Y-124900D02*
Y-116900D01*
X720033D01*
X720833Y-117300D01*
X721433Y-117833D01*
X721933Y-118633D01*
X722333Y-119567D01*
X722433Y-120900D01*
X722333Y-122233D01*
X721933Y-123167D01*
X721433Y-123967D01*
X720833Y-124500D01*
X720033Y-124900D01*
X718033D01*
G01X728233D02*
Y-116900D01*
X727033Y-118500D01*
G01Y-124900D02*
X729433D01*
G01X734333Y-121567D02*
X735033Y-120633D01*
X735633Y-120100D01*
X736433Y-119833D01*
X737133Y-120100D01*
X737633Y-120633D01*
X738033Y-121433D01*
X738133Y-122367D01*
X738033Y-123167D01*
X737633Y-123967D01*
X737033Y-124633D01*
X736333Y-124900D01*
X735533Y-124633D01*
X734833Y-123834D01*
X734433Y-122633D01*
X734333Y-121300D01*
X734533Y-119567D01*
X734833Y-118633D01*
X735333Y-117700D01*
X736033Y-117033D01*
X736733Y-116900D01*
X737433Y-117167D01*
X737933Y-117833D01*
G01X742133Y-124900D02*
X746333Y-116900D01*
G01X742133D02*
X746333Y-124900D01*
G01X753433D02*
Y-116900D01*
X749733Y-122633D01*
X754733D01*
G01X760733Y-127567D02*
X761733Y-126233D01*
X762233Y-124900D01*
Y-119567D01*
X761733Y-118233D01*
X760733Y-116900D01*
G01X621533Y101700D02*
Y109700D01*
X624033D01*
X624833Y109300D01*
X625333Y108767D01*
X625533Y107700D01*
X625333Y106633D01*
X624733Y105967D01*
X624033Y105567D01*
X621533D01*
G01X624033D02*
X625533Y101700D01*
G01X633533D02*
X629533D01*
Y109700D01*
X633533D01*
G01X631933Y105833D02*
X629533D01*
G01X641733Y109033D02*
X641133Y109433D01*
X640433Y109700D01*
X639633D01*
X638733Y109300D01*
X638033Y108633D01*
X637533Y107833D01*
X637133Y106500D01*
X637033Y105300D01*
X637233Y104100D01*
X637533Y103300D01*
X638133Y102500D01*
X638833Y101967D01*
X639533Y101700D01*
X640233D01*
X640933Y101967D01*
X641533Y102367D01*
X642033Y102900D01*
G01X647533Y109700D02*
Y101700D01*
G01X645233Y109700D02*
X649833D01*
G01X653033Y101700D02*
X655533Y109700D01*
X658033Y101700D01*
G01X657133Y104500D02*
X653933D01*
G01X661233Y101700D02*
Y109700D01*
X665833Y101700D01*
Y109700D01*
G01X672133Y105700D02*
X674133D01*
Y103300D01*
X673533Y102500D01*
X672833Y101967D01*
X671833Y101700D01*
X670833Y101967D01*
X670133Y102500D01*
X669533Y103300D01*
X669133Y104233D01*
X668933Y105300D01*
Y106233D01*
X669133Y107033D01*
X669533Y107967D01*
X670133Y108767D01*
X670733Y109300D01*
X671533Y109700D01*
X672233D01*
X673033Y109433D01*
X673633Y108900D01*
G01X677533Y109700D02*
Y101700D01*
X681533D01*
G01X689533D02*
X685533D01*
Y109700D01*
X689533D01*
G01X687933Y105833D02*
X685533D01*
G01X701333Y101700D02*
Y109700D01*
X703333D01*
X704133Y109300D01*
X704733Y108767D01*
X705233Y107967D01*
X705633Y107033D01*
X705733Y105700D01*
X705633Y104367D01*
X705233Y103433D01*
X704733Y102633D01*
X704133Y102100D01*
X703333Y101700D01*
X701333D01*
G01X709533D02*
Y109700D01*
X712033D01*
X712833Y109300D01*
X713333Y108767D01*
X713533Y107700D01*
X713333Y106633D01*
X712733Y105967D01*
X712033Y105567D01*
X709533D01*
G01X712033D02*
X713533Y101700D01*
G01X718333Y109700D02*
X720733D01*
G01X719533D02*
Y101700D01*
G01X718333D02*
X720733D01*
G01X725533Y109700D02*
Y101700D01*
X729533D01*
G01X733533Y109700D02*
Y101700D01*
X737533D01*
G01X749433D02*
Y109700D01*
G01X753633D02*
Y101700D01*
G01Y105700D02*
X749433D01*
G01X759533Y101700D02*
X758733Y101833D01*
X758033Y102367D01*
X757433Y103167D01*
X757033Y104100D01*
X756833Y105167D01*
Y106233D01*
X757033Y107300D01*
X757433Y108233D01*
X758033Y109033D01*
X758733Y109567D01*
X759533Y109700D01*
X760333Y109567D01*
X761033Y109033D01*
X761633Y108233D01*
X762033Y107300D01*
X762233Y106233D01*
Y105167D01*
X762033Y104100D01*
X761633Y103167D01*
X761033Y102367D01*
X760333Y101833D01*
X759533Y101700D01*
G01X765533Y109700D02*
Y101700D01*
X769533D01*
G01X777533D02*
X773533D01*
Y109700D01*
X777533D01*
G01X775933Y105833D02*
X773533D01*
G01X789333Y101700D02*
Y109700D01*
X791333D01*
X792133Y109300D01*
X792733Y108767D01*
X793233Y107967D01*
X793633Y107033D01*
X793733Y105700D01*
X793633Y104367D01*
X793233Y103433D01*
X792733Y102633D01*
X792133Y102100D01*
X791333Y101700D01*
X789333D01*
G01X798033Y105300D02*
X801233D01*
X800933Y106233D01*
X800433Y106767D01*
X799733Y107033D01*
X799033Y106900D01*
X798433Y106500D01*
X798033Y105567D01*
X797833Y104766D01*
Y103967D01*
X798033Y103167D01*
X798533Y102367D01*
X799133Y101833D01*
X799833Y101700D01*
X800533Y101967D01*
X801233Y102766D01*
G01X806933Y101700D02*
Y108500D01*
X807133Y109167D01*
X807533Y109567D01*
X808133Y109700D01*
X808733Y109433D01*
X809033Y108767D01*
G01X807833Y106500D02*
X805833D01*
G01X815533Y107033D02*
Y101700D01*
G01Y109167D02*
X815333Y109300D01*
Y109567D01*
X815533Y109700D01*
X815733Y109567D01*
Y109300D01*
X815533Y109167D01*
G01X821833Y101700D02*
Y107033D01*
G01Y105700D02*
X822233Y106367D01*
X822833Y106900D01*
X823633Y107033D01*
X824333Y106900D01*
X824933Y106367D01*
X825233Y105433D01*
Y101700D01*
G01X830033Y105300D02*
X833233D01*
X832933Y106233D01*
X832433Y106767D01*
X831733Y107033D01*
X831033Y106900D01*
X830433Y106500D01*
X830033Y105567D01*
X829833Y104766D01*
Y103967D01*
X830033Y103167D01*
X830533Y102367D01*
X831133Y101833D01*
X831833Y101700D01*
X832533Y101967D01*
X833233Y102766D01*
G01X663333Y-388000D02*
Y-396000D01*
G01X661933Y-390667D02*
X664733D01*
G01X669633Y-396000D02*
Y-388000D01*
G01Y-391867D02*
X670133Y-391200D01*
X670633Y-390800D01*
X671433Y-390667D01*
X672033Y-390800D01*
X672733Y-391333D01*
X673033Y-392133D01*
Y-396000D01*
G01X677833Y-392400D02*
X681033D01*
X680733Y-391467D01*
X680233Y-390933D01*
X679533Y-390667D01*
X678833Y-390800D01*
X678233Y-391200D01*
X677833Y-392133D01*
X677633Y-392934D01*
Y-393733D01*
X677833Y-394533D01*
X678333Y-395333D01*
X678933Y-395867D01*
X679633Y-396000D01*
X680333Y-395733D01*
X681033Y-394934D01*
G01X693933Y-396000D02*
Y-390667D01*
G01Y-391733D02*
X694433Y-391200D01*
X694933Y-390800D01*
X695633Y-390667D01*
X696133Y-390800D01*
X696733Y-391200D01*
G01X701833Y-392400D02*
X705033D01*
X704733Y-391467D01*
X704233Y-390933D01*
X703533Y-390667D01*
X702833Y-390800D01*
X702233Y-391200D01*
X701833Y-392133D01*
X701633Y-392934D01*
Y-393733D01*
X701833Y-394533D01*
X702333Y-395333D01*
X702933Y-395867D01*
X703633Y-396000D01*
X704333Y-395733D01*
X705033Y-394934D01*
G01X711333Y-396000D02*
Y-388000D01*
G01X721133Y-396000D02*
Y-390667D01*
G01Y-391600D02*
X720733Y-391067D01*
X720133Y-390800D01*
X719433Y-390667D01*
X718733Y-390933D01*
X718133Y-391467D01*
X717733Y-392267D01*
X717533Y-393333D01*
X717733Y-394400D01*
X718133Y-395200D01*
X718733Y-395733D01*
X719433Y-396000D01*
X720133Y-395867D01*
X720733Y-395467D01*
X721133Y-394934D01*
G01X727333Y-388000D02*
Y-396000D01*
G01X725933Y-390667D02*
X728733D01*
G01X735333D02*
Y-396000D01*
G01Y-388533D02*
X735133Y-388400D01*
Y-388133D01*
X735333Y-388000D01*
X735533Y-388133D01*
Y-388400D01*
X735333Y-388533D01*
G01X741533Y-390667D02*
X743333Y-396000D01*
X745133Y-390667D01*
G01X749833Y-392400D02*
X753033D01*
X752733Y-391467D01*
X752233Y-390933D01*
X751533Y-390667D01*
X750833Y-390800D01*
X750233Y-391200D01*
X749833Y-392133D01*
X749633Y-392934D01*
Y-393733D01*
X749833Y-394533D01*
X750333Y-395333D01*
X750933Y-395867D01*
X751633Y-396000D01*
X752333Y-395733D01*
X753033Y-394934D01*
G01X767333Y-396000D02*
Y-388000D01*
G01X775333Y-396000D02*
X774733Y-395867D01*
X774133Y-395333D01*
X773733Y-394400D01*
X773533Y-393333D01*
X773733Y-392267D01*
X774133Y-391333D01*
X774733Y-390800D01*
X775333Y-390667D01*
X775933Y-390800D01*
X776533Y-391333D01*
X776933Y-392267D01*
X777033Y-393333D01*
X776933Y-394400D01*
X776533Y-395333D01*
X775933Y-395867D01*
X775333Y-396000D01*
G01X784933Y-391333D02*
X784233Y-390800D01*
X783633Y-390667D01*
X782833Y-390933D01*
X782233Y-391467D01*
X781833Y-392400D01*
X781733Y-393333D01*
X781833Y-394267D01*
X782233Y-395067D01*
X782833Y-395733D01*
X783633Y-396000D01*
X784333Y-395733D01*
X784933Y-395200D01*
G01X793133Y-396000D02*
Y-390667D01*
G01Y-391600D02*
X792733Y-391067D01*
X792133Y-390800D01*
X791433Y-390667D01*
X790733Y-390933D01*
X790133Y-391467D01*
X789733Y-392267D01*
X789533Y-393333D01*
X789733Y-394400D01*
X790133Y-395200D01*
X790733Y-395733D01*
X791433Y-396000D01*
X792133Y-395867D01*
X792733Y-395467D01*
X793133Y-394934D01*
G01X799333Y-388000D02*
Y-396000D01*
G01X797933Y-390667D02*
X800733D01*
G01X807333D02*
Y-396000D01*
G01Y-388533D02*
X807133Y-388400D01*
Y-388133D01*
X807333Y-388000D01*
X807533Y-388133D01*
Y-388400D01*
X807333Y-388533D01*
G01X815333Y-396000D02*
X814733Y-395867D01*
X814133Y-395333D01*
X813733Y-394400D01*
X813533Y-393333D01*
X813733Y-392267D01*
X814133Y-391333D01*
X814733Y-390800D01*
X815333Y-390667D01*
X815933Y-390800D01*
X816533Y-391333D01*
X816933Y-392267D01*
X817033Y-393333D01*
X816933Y-394400D01*
X816533Y-395333D01*
X815933Y-395867D01*
X815333Y-396000D01*
G01X821633D02*
Y-390667D01*
G01Y-392000D02*
X822033Y-391333D01*
X822633Y-390800D01*
X823433Y-390667D01*
X824133Y-390800D01*
X824733Y-391333D01*
X825033Y-392267D01*
Y-396000D01*
G01X839333D02*
X838733Y-395867D01*
X838133Y-395333D01*
X837733Y-394400D01*
X837533Y-393333D01*
X837733Y-392267D01*
X838133Y-391333D01*
X838733Y-390800D01*
X839333Y-390667D01*
X839933Y-390800D01*
X840533Y-391333D01*
X840933Y-392267D01*
X841033Y-393333D01*
X840933Y-394400D01*
X840533Y-395333D01*
X839933Y-395867D01*
X839333Y-396000D01*
G01X846733D02*
Y-389200D01*
X846933Y-388533D01*
X847333Y-388133D01*
X847933Y-388000D01*
X848533Y-388267D01*
X848833Y-388933D01*
G01X847633Y-391200D02*
X845633D01*
G01X861633Y-396000D02*
Y-388000D01*
G01Y-391867D02*
X862133Y-391200D01*
X862633Y-390800D01*
X863433Y-390667D01*
X864033Y-390800D01*
X864733Y-391333D01*
X865033Y-392133D01*
Y-396000D01*
G01X871333D02*
X870733Y-395867D01*
X870133Y-395333D01*
X869733Y-394400D01*
X869533Y-393333D01*
X869733Y-392267D01*
X870133Y-391333D01*
X870733Y-390800D01*
X871333Y-390667D01*
X871933Y-390800D01*
X872533Y-391333D01*
X872933Y-392267D01*
X873033Y-393333D01*
X872933Y-394400D01*
X872533Y-395333D01*
X871933Y-395867D01*
X871333Y-396000D01*
G01X879333D02*
Y-388000D01*
G01X885833Y-392400D02*
X889033D01*
X888733Y-391467D01*
X888233Y-390933D01*
X887533Y-390667D01*
X886833Y-390800D01*
X886233Y-391200D01*
X885833Y-392133D01*
X885633Y-392934D01*
Y-393733D01*
X885833Y-394533D01*
X886333Y-395333D01*
X886933Y-395867D01*
X887633Y-396000D01*
X888333Y-395733D01*
X889033Y-394934D01*
G01X903333Y-388000D02*
Y-396000D01*
G01X901933Y-390667D02*
X904733D01*
G01X911333Y-396000D02*
X910733Y-395867D01*
X910133Y-395333D01*
X909733Y-394400D01*
X909533Y-393333D01*
X909733Y-392267D01*
X910133Y-391333D01*
X910733Y-390800D01*
X911333Y-390667D01*
X911933Y-390800D01*
X912533Y-391333D01*
X912933Y-392267D01*
X913033Y-393333D01*
X912933Y-394400D01*
X912533Y-395333D01*
X911933Y-395867D01*
X911333Y-396000D01*
G01X925633D02*
Y-388000D01*
G01Y-391867D02*
X926133Y-391200D01*
X926633Y-390800D01*
X927433Y-390667D01*
X928033Y-390800D01*
X928733Y-391333D01*
X929033Y-392133D01*
Y-396000D01*
G01X935333D02*
X934733Y-395867D01*
X934133Y-395333D01*
X933733Y-394400D01*
X933533Y-393333D01*
X933733Y-392267D01*
X934133Y-391333D01*
X934733Y-390800D01*
X935333Y-390667D01*
X935933Y-390800D01*
X936533Y-391333D01*
X936933Y-392267D01*
X937033Y-393333D01*
X936933Y-394400D01*
X936533Y-395333D01*
X935933Y-395867D01*
X935333Y-396000D01*
G01X943333D02*
Y-388000D01*
G01X949833Y-392400D02*
X953033D01*
X952733Y-391467D01*
X952233Y-390933D01*
X951533Y-390667D01*
X950833Y-390800D01*
X950233Y-391200D01*
X949833Y-392133D01*
X949633Y-392934D01*
Y-393733D01*
X949833Y-394533D01*
X950333Y-395333D01*
X950933Y-395867D01*
X951633Y-396000D01*
X952333Y-395733D01*
X953033Y-394934D01*
G01X662333Y-142600D02*
Y-134600D01*
X664333D01*
X665133Y-135000D01*
X665733Y-135533D01*
X666233Y-136333D01*
X666633Y-137267D01*
X666733Y-138600D01*
X666633Y-139933D01*
X666233Y-140867D01*
X665733Y-141667D01*
X665133Y-142200D01*
X664333Y-142600D01*
X662333D01*
G01X672533D02*
Y-134600D01*
X671333Y-136200D01*
G01Y-142600D02*
X673733D01*
G01X678633Y-139267D02*
X679333Y-138333D01*
X679933Y-137800D01*
X680733Y-137533D01*
X681433Y-137800D01*
X681933Y-138333D01*
X682333Y-139133D01*
X682433Y-140067D01*
X682333Y-140867D01*
X681933Y-141667D01*
X681333Y-142333D01*
X680633Y-142600D01*
X679833Y-142333D01*
X679133Y-141534D01*
X678733Y-140333D01*
X678633Y-139000D01*
X678833Y-137267D01*
X679133Y-136333D01*
X679633Y-135400D01*
X680333Y-134733D01*
X681033Y-134600D01*
X681733Y-134867D01*
X682233Y-135533D01*
G01X687233Y-141133D02*
X689833D01*
G01Y-138733D02*
X687233D01*
G01X694333Y-142600D02*
Y-134600D01*
X696333D01*
X697133Y-135000D01*
X697733Y-135533D01*
X698233Y-136333D01*
X698633Y-137267D01*
X698733Y-138600D01*
X698633Y-139933D01*
X698233Y-140867D01*
X697733Y-141667D01*
X697133Y-142200D01*
X696333Y-142600D01*
X694333D01*
G01X704533Y-137267D02*
Y-142600D01*
G01Y-135133D02*
X704333Y-135000D01*
Y-134733D01*
X704533Y-134600D01*
X704733Y-134733D01*
Y-135000D01*
X704533Y-135133D01*
G01X714333Y-142600D02*
Y-137267D01*
G01Y-138200D02*
X713933Y-137667D01*
X713333Y-137400D01*
X712633Y-137267D01*
X711933Y-137533D01*
X711333Y-138067D01*
X710933Y-138867D01*
X710733Y-139933D01*
X710933Y-141000D01*
X711333Y-141800D01*
X711933Y-142333D01*
X712633Y-142600D01*
X713333Y-142467D01*
X713933Y-142067D01*
X714333Y-141534D01*
G01X717533Y-142600D02*
Y-137267D01*
G01Y-138733D02*
X717833Y-138067D01*
X718333Y-137533D01*
X719033Y-137267D01*
X719733Y-137533D01*
X720233Y-138067D01*
X720533Y-138733D01*
Y-142600D01*
G01Y-138733D02*
X720833Y-138067D01*
X721333Y-137533D01*
X722033Y-137267D01*
X722733Y-137533D01*
X723233Y-138067D01*
X723533Y-138867D01*
Y-142600D01*
G01X727033Y-139000D02*
X730233D01*
X729933Y-138067D01*
X729433Y-137533D01*
X728733Y-137267D01*
X728033Y-137400D01*
X727433Y-137800D01*
X727033Y-138733D01*
X726833Y-139534D01*
Y-140333D01*
X727033Y-141133D01*
X727533Y-141933D01*
X728133Y-142467D01*
X728833Y-142600D01*
X729533Y-142333D01*
X730233Y-141534D01*
G01X736533Y-134600D02*
Y-142600D01*
G01X735133Y-137267D02*
X737933D01*
G01X743033Y-139000D02*
X746233D01*
X745933Y-138067D01*
X745433Y-137533D01*
X744733Y-137267D01*
X744033Y-137400D01*
X743433Y-137800D01*
X743033Y-138733D01*
X742833Y-139534D01*
Y-140333D01*
X743033Y-141133D01*
X743533Y-141933D01*
X744133Y-142467D01*
X744833Y-142600D01*
X745533Y-142333D01*
X746233Y-141534D01*
G01X751133Y-142600D02*
Y-137267D01*
G01Y-138333D02*
X751633Y-137800D01*
X752133Y-137400D01*
X752833Y-137267D01*
X753333Y-137400D01*
X753933Y-137800D01*
G01X768533Y-142600D02*
Y-134600D01*
X767333Y-136200D01*
G01Y-142600D02*
X769733D01*
G01X774633Y-139267D02*
X775333Y-138333D01*
X775933Y-137800D01*
X776733Y-137533D01*
X777433Y-137800D01*
X777933Y-138333D01*
X778333Y-139133D01*
X778433Y-140067D01*
X778333Y-140867D01*
X777933Y-141667D01*
X777333Y-142333D01*
X776633Y-142600D01*
X775833Y-142333D01*
X775133Y-141534D01*
X774733Y-140333D01*
X774633Y-139000D01*
X774833Y-137267D01*
X775133Y-136333D01*
X775633Y-135400D01*
X776333Y-134733D01*
X777033Y-134600D01*
X777733Y-134867D01*
X778233Y-135533D01*
G01X789533Y-142600D02*
Y-137267D01*
G01Y-138733D02*
X789833Y-138067D01*
X790333Y-137533D01*
X791033Y-137267D01*
X791733Y-137533D01*
X792233Y-138067D01*
X792533Y-138733D01*
Y-142600D01*
G01Y-138733D02*
X792833Y-138067D01*
X793333Y-137533D01*
X794033Y-137267D01*
X794733Y-137533D01*
X795233Y-138067D01*
X795533Y-138867D01*
Y-142600D01*
G01X800533Y-137267D02*
Y-142600D01*
G01Y-135133D02*
X800333Y-135000D01*
Y-134733D01*
X800533Y-134600D01*
X800733Y-134733D01*
Y-135000D01*
X800533Y-135133D01*
G01X808533Y-142600D02*
Y-134600D01*
G01X815033Y-141667D02*
X815533Y-142200D01*
X816233Y-142600D01*
X816833D01*
X817433Y-142333D01*
X817833Y-141933D01*
X818033Y-141400D01*
X817933Y-140600D01*
X817533Y-140200D01*
X815733Y-139400D01*
X815333Y-138467D01*
X815533Y-137800D01*
X815933Y-137400D01*
X816533Y-137267D01*
X817133Y-137400D01*
X817733Y-137800D01*
G01X660733Y-91300D02*
Y-83300D01*
X662733D01*
X663533Y-83700D01*
X664133Y-84233D01*
X664633Y-85033D01*
X665033Y-85967D01*
X665133Y-87300D01*
X665033Y-88633D01*
X664633Y-89567D01*
X664133Y-90367D01*
X663533Y-90900D01*
X662733Y-91300D01*
X660733D01*
G01X670933D02*
Y-83300D01*
X669733Y-84900D01*
G01Y-91300D02*
X672133D01*
G01X677033Y-87967D02*
X677733Y-87033D01*
X678333Y-86500D01*
X679133Y-86233D01*
X679833Y-86500D01*
X680333Y-87033D01*
X680733Y-87833D01*
X680833Y-88767D01*
X680733Y-89567D01*
X680333Y-90367D01*
X679733Y-91033D01*
X679033Y-91300D01*
X678233Y-91033D01*
X677533Y-90234D01*
X677133Y-89033D01*
X677033Y-87700D01*
X677233Y-85967D01*
X677533Y-85033D01*
X678033Y-84100D01*
X678733Y-83433D01*
X679433Y-83300D01*
X680133Y-83567D01*
X680633Y-84233D01*
G01X706838Y-87290D02*
X703137Y-83589D01*
G01X697433Y-87300D02*
X706838Y-87290D01*
G01D02*
X703438Y-90689D01*
G01X707833Y-86800D02*
Y30600D01*
G01Y-86800D02*
G03X708633Y-87600I800J0D01*
G01X786433D02*
X708633D01*
G01Y31400D02*
X786433D01*
G01X708633D02*
G03X707833Y30600I0J-800D01*
G01Y32600D02*
Y70600D01*
G01X708333Y59300D02*
X710433Y61400D01*
G01X708533Y59100D02*
X708333Y59300D01*
G01X735233Y59100D02*
X708533D01*
G01X708433Y59000D02*
X710233Y57200D01*
G01X708433Y59100D02*
Y59000D01*
G01X739833Y54700D02*
Y62700D01*
X736133Y56967D01*
X741133D01*
G01X744433Y55900D02*
X745033Y55233D01*
X745733Y54833D01*
X746633Y54700D01*
X747533Y54967D01*
X748233Y55500D01*
X748733Y56433D01*
X748833Y57500D01*
X748633Y58567D01*
X748133Y59233D01*
X747433Y59767D01*
X746733Y59900D01*
X746033Y59767D01*
X745133Y59233D01*
X745433Y62700D01*
X748133D01*
G01X758433Y58800D02*
X786533D01*
G01X809633Y-373500D02*
X812033D01*
G01X810833D02*
Y-381500D01*
G01X809633D02*
X812033D01*
G01X818833Y-373500D02*
Y-381500D01*
G01X817433Y-376167D02*
X820233D01*
G01X825333Y-377900D02*
X828533D01*
X828233Y-376967D01*
X827733Y-376433D01*
X827033Y-376167D01*
X826333Y-376300D01*
X825733Y-376700D01*
X825333Y-377633D01*
X825133Y-378434D01*
Y-379233D01*
X825333Y-380033D01*
X825833Y-380833D01*
X826433Y-381367D01*
X827133Y-381500D01*
X827833Y-381233D01*
X828533Y-380434D01*
G01X831833Y-381500D02*
Y-376167D01*
G01Y-377633D02*
X832133Y-376967D01*
X832633Y-376433D01*
X833333Y-376167D01*
X834033Y-376433D01*
X834533Y-376967D01*
X834833Y-377633D01*
Y-381500D01*
G01Y-377633D02*
X835133Y-376967D01*
X835633Y-376433D01*
X836333Y-376167D01*
X837033Y-376433D01*
X837533Y-376967D01*
X837833Y-377767D01*
Y-381500D01*
G01X841333Y-380567D02*
X841833Y-381100D01*
X842533Y-381500D01*
X843133D01*
X843733Y-381233D01*
X844133Y-380833D01*
X844333Y-380300D01*
X844233Y-379500D01*
X843833Y-379100D01*
X842033Y-378300D01*
X841633Y-377367D01*
X841833Y-376700D01*
X842233Y-376300D01*
X842833Y-376167D01*
X843433Y-376300D01*
X844033Y-376700D01*
G01X786433Y-87600D02*
G03X787233Y-86800I0J800D01*
G01Y30600D02*
Y-86800D01*
G01X787833Y-87600D02*
X882233D01*
G01X841233Y-87300D02*
X837333Y-83400D01*
G01X832433Y-31267D02*
X833133Y-31933D01*
X833933Y-32200D01*
X834733Y-31933D01*
X835433Y-31134D01*
X835933Y-29933D01*
X836133Y-28733D01*
Y-27267D01*
X835933Y-26067D01*
X835433Y-25000D01*
X834833Y-24467D01*
X834133Y-24200D01*
X833333Y-24467D01*
X832733Y-25000D01*
X832333Y-25800D01*
X832133Y-26867D01*
X832333Y-27800D01*
X832833Y-28733D01*
X833433Y-29267D01*
X834133Y-29400D01*
X834933Y-29134D01*
X835533Y-28467D01*
X836133Y-27267D01*
G01X840233Y-28867D02*
X840933Y-27933D01*
X841533Y-27400D01*
X842333Y-27133D01*
X843033Y-27400D01*
X843533Y-27933D01*
X843933Y-28733D01*
X844033Y-29667D01*
X843933Y-30467D01*
X843533Y-31267D01*
X842933Y-31933D01*
X842233Y-32200D01*
X841433Y-31933D01*
X840733Y-31134D01*
X840333Y-29933D01*
X840233Y-28600D01*
X840433Y-26867D01*
X840733Y-25933D01*
X841233Y-25000D01*
X841933Y-24333D01*
X842633Y-24200D01*
X843333Y-24467D01*
X843833Y-25133D01*
G01X787233Y30600D02*
G03X786433Y31400I-800J0D01*
G01X788633D02*
X877933D01*
G01X787233Y32700D02*
X787133Y70800D01*
G01X842033Y31200D02*
X838633Y27800D01*
G01X783933Y61800D02*
X783833D01*
G01X786733Y59000D02*
X783933Y61800D01*
G01X786533Y58800D02*
X786733Y59000D01*
G01X786633Y58800D02*
X784033Y56200D01*
G01X786633Y58900D02*
Y58800D01*
G01X882233Y-87600D02*
X882833Y-88200D01*
G01X841733Y-87300D02*
X841233D01*
G01X841633Y-87100D02*
X841033Y-87700D01*
G01X841633Y-37800D02*
Y-87100D01*
G01X842033Y-87200D02*
X845633Y-83600D01*
G01X841833Y-87200D02*
X842033D01*
G01X877933Y31400D02*
X878433Y31900D01*
G01X842133Y30700D02*
X842233Y-18800D01*
G01X842133Y31100D02*
X845333Y27900D01*
G01X1106070Y-505633D02*
X1108470D01*
G01X1107170Y-503900D02*
Y-507367D01*
G01X1113370Y-508567D02*
X1116970Y-500300D01*
G01X1121870Y-505633D02*
X1124470D01*
G01X1128970Y-507100D02*
X1129570Y-507767D01*
X1130270Y-508167D01*
X1131170Y-508300D01*
X1132070Y-508033D01*
X1132770Y-507500D01*
X1133270Y-506567D01*
X1133370Y-505500D01*
X1133170Y-504433D01*
X1132670Y-503767D01*
X1131970Y-503233D01*
X1131270Y-503100D01*
X1130570Y-503233D01*
X1129670Y-503767D01*
X1129970Y-500300D01*
X1132670D01*
G01X1136170Y-508300D02*
Y-502967D01*
G01Y-504433D02*
X1136470Y-503767D01*
X1136970Y-503233D01*
X1137670Y-502967D01*
X1138370Y-503233D01*
X1138870Y-503767D01*
X1139170Y-504433D01*
Y-508300D01*
G01Y-504433D02*
X1139470Y-503767D01*
X1139970Y-503233D01*
X1140670Y-502967D01*
X1141370Y-503233D01*
X1141870Y-503767D01*
X1142170Y-504567D01*
Y-508300D01*
G01X1147170Y-502967D02*
Y-508300D01*
G01Y-500833D02*
X1146970Y-500700D01*
Y-500433D01*
X1147170Y-500300D01*
X1147370Y-500433D01*
Y-500700D01*
X1147170Y-500833D01*
G01X1155170Y-508300D02*
Y-500300D01*
G01X1106070Y-518633D02*
X1108470D01*
G01X1107170Y-516900D02*
Y-520367D01*
G01X1113370Y-521567D02*
X1116970Y-513300D01*
G01X1121870Y-518633D02*
X1124470D01*
G01X1128970Y-520100D02*
X1129570Y-520767D01*
X1130270Y-521167D01*
X1131170Y-521300D01*
X1132070Y-521033D01*
X1132770Y-520500D01*
X1133270Y-519567D01*
X1133370Y-518500D01*
X1133170Y-517433D01*
X1132670Y-516767D01*
X1131970Y-516233D01*
X1131270Y-516100D01*
X1130570Y-516233D01*
X1129670Y-516767D01*
X1129970Y-513300D01*
X1132670D01*
G01X1136170Y-521300D02*
Y-515967D01*
G01Y-517433D02*
X1136470Y-516767D01*
X1136970Y-516233D01*
X1137670Y-515967D01*
X1138370Y-516233D01*
X1138870Y-516767D01*
X1139170Y-517433D01*
Y-521300D01*
G01Y-517433D02*
X1139470Y-516767D01*
X1139970Y-516233D01*
X1140670Y-515967D01*
X1141370Y-516233D01*
X1141870Y-516767D01*
X1142170Y-517567D01*
Y-521300D01*
G01X1147170Y-515967D02*
Y-521300D01*
G01Y-513833D02*
X1146970Y-513700D01*
Y-513433D01*
X1147170Y-513300D01*
X1147370Y-513433D01*
Y-513700D01*
X1147170Y-513833D01*
G01X1155170Y-521300D02*
Y-513300D01*
G01X1105433Y-533600D02*
Y-525600D01*
X1104233Y-527200D01*
G01Y-533600D02*
X1106633D01*
G01X1113433Y-533867D02*
X1113233Y-533733D01*
Y-533467D01*
X1113433Y-533333D01*
X1113633Y-533467D01*
Y-533733D01*
X1113433Y-533867D01*
G01X1121433Y-525600D02*
X1120633Y-525867D01*
X1120033Y-526533D01*
X1119633Y-527333D01*
X1119333Y-528400D01*
X1119233Y-529600D01*
X1119333Y-530800D01*
X1119633Y-531867D01*
X1120033Y-532667D01*
X1120633Y-533333D01*
X1121433Y-533600D01*
X1122233Y-533333D01*
X1122833Y-532667D01*
X1123233Y-531867D01*
X1123533Y-530800D01*
X1123633Y-529600D01*
X1123533Y-528400D01*
X1123233Y-527333D01*
X1122833Y-526533D01*
X1122233Y-525867D01*
X1121433Y-525600D01*
G01X1126433Y-533600D02*
Y-528267D01*
G01Y-529733D02*
X1126733Y-529067D01*
X1127233Y-528533D01*
X1127933Y-528267D01*
X1128633Y-528533D01*
X1129133Y-529067D01*
X1129433Y-529733D01*
Y-533600D01*
G01Y-529733D02*
X1129733Y-529067D01*
X1130233Y-528533D01*
X1130933Y-528267D01*
X1131633Y-528533D01*
X1132133Y-529067D01*
X1132433Y-529867D01*
Y-533600D01*
G01X1137433Y-528267D02*
Y-533600D01*
G01Y-526133D02*
X1137233Y-526000D01*
Y-525733D01*
X1137433Y-525600D01*
X1137633Y-525733D01*
Y-526000D01*
X1137433Y-526133D01*
G01X1145433Y-533600D02*
Y-525600D01*
G01X1158433Y-533600D02*
Y-528267D01*
G01Y-529733D02*
X1158733Y-529067D01*
X1159233Y-528533D01*
X1159933Y-528267D01*
X1160633Y-528533D01*
X1161133Y-529067D01*
X1161433Y-529733D01*
Y-533600D01*
G01Y-529733D02*
X1161733Y-529067D01*
X1162233Y-528533D01*
X1162933Y-528267D01*
X1163633Y-528533D01*
X1164133Y-529067D01*
X1164433Y-529867D01*
Y-533600D01*
G01X1171233D02*
Y-528267D01*
G01Y-529200D02*
X1170833Y-528667D01*
X1170233Y-528400D01*
X1169533Y-528267D01*
X1168833Y-528533D01*
X1168233Y-529067D01*
X1167833Y-529867D01*
X1167633Y-530933D01*
X1167833Y-532000D01*
X1168233Y-532800D01*
X1168833Y-533333D01*
X1169533Y-533600D01*
X1170233Y-533467D01*
X1170833Y-533067D01*
X1171233Y-532534D01*
G01X1175933Y-528267D02*
X1178933Y-533600D01*
G01Y-528267D02*
X1175933Y-533600D01*
G01X1106070Y-456072D02*
X1108470D01*
G01X1107170Y-454339D02*
Y-457806D01*
G01X1113370Y-459006D02*
X1116970Y-450739D01*
G01X1121870Y-456072D02*
X1124470D01*
G01X1128970Y-457139D02*
X1129570Y-458072D01*
X1130370Y-458606D01*
X1131270Y-458739D01*
X1132070Y-458606D01*
X1132870Y-457939D01*
X1133370Y-457139D01*
X1133470Y-456339D01*
X1133270Y-455406D01*
X1132570Y-454739D01*
X1131870Y-454472D01*
X1130970D01*
G01X1131870D02*
X1132470Y-454072D01*
X1132970Y-453406D01*
X1133170Y-452606D01*
X1132970Y-451806D01*
X1132470Y-451139D01*
X1131570Y-450739D01*
X1130670Y-450872D01*
X1129770Y-451406D01*
G01X1136170Y-458739D02*
Y-453406D01*
G01Y-454872D02*
X1136470Y-454206D01*
X1136970Y-453672D01*
X1137670Y-453406D01*
X1138370Y-453672D01*
X1138870Y-454206D01*
X1139170Y-454872D01*
Y-458739D01*
G01Y-454872D02*
X1139470Y-454206D01*
X1139970Y-453672D01*
X1140670Y-453406D01*
X1141370Y-453672D01*
X1141870Y-454206D01*
X1142170Y-455006D01*
Y-458739D01*
G01X1147170Y-453406D02*
Y-458739D01*
G01Y-451272D02*
X1146970Y-451139D01*
Y-450872D01*
X1147170Y-450739D01*
X1147370Y-450872D01*
Y-451139D01*
X1147170Y-451272D01*
G01X1155170Y-458739D02*
Y-450739D01*
G01X1104433Y-443333D02*
X1106833D01*
G01X1105533Y-441600D02*
Y-445067D01*
G01X1111733Y-446267D02*
X1115333Y-438000D01*
G01X1120233Y-443333D02*
X1122833D01*
G01X1127633Y-439333D02*
X1128233Y-438533D01*
X1128933Y-438133D01*
X1129733Y-438000D01*
X1130733Y-438267D01*
X1131433Y-438933D01*
X1131633Y-439733D01*
X1131533Y-440534D01*
X1131133Y-441200D01*
X1129133Y-442533D01*
X1128233Y-443467D01*
X1127633Y-444800D01*
X1127433Y-446000D01*
X1131633D01*
G01X1134533D02*
Y-440667D01*
G01Y-442133D02*
X1134833Y-441467D01*
X1135333Y-440933D01*
X1136033Y-440667D01*
X1136733Y-440933D01*
X1137233Y-441467D01*
X1137533Y-442133D01*
Y-446000D01*
G01Y-442133D02*
X1137833Y-441467D01*
X1138333Y-440933D01*
X1139033Y-440667D01*
X1139733Y-440933D01*
X1140233Y-441467D01*
X1140533Y-442267D01*
Y-446000D01*
G01X1145533Y-440667D02*
Y-446000D01*
G01Y-438533D02*
X1145333Y-438400D01*
Y-438133D01*
X1145533Y-438000D01*
X1145733Y-438133D01*
Y-438400D01*
X1145533Y-438533D01*
G01X1153533Y-446000D02*
Y-438000D01*
G01X1106070Y-468633D02*
X1108470D01*
G01X1107170Y-466900D02*
Y-470367D01*
G01X1113370Y-471567D02*
X1116970Y-463300D01*
G01X1121870Y-468633D02*
X1124470D01*
G01X1129270Y-464633D02*
X1129870Y-463833D01*
X1130570Y-463433D01*
X1131370Y-463300D01*
X1132370Y-463567D01*
X1133070Y-464233D01*
X1133270Y-465033D01*
X1133170Y-465834D01*
X1132770Y-466500D01*
X1130770Y-467833D01*
X1129870Y-468767D01*
X1129270Y-470100D01*
X1129070Y-471300D01*
X1133270D01*
G01X1136170D02*
Y-465967D01*
G01Y-467433D02*
X1136470Y-466767D01*
X1136970Y-466233D01*
X1137670Y-465967D01*
X1138370Y-466233D01*
X1138870Y-466767D01*
X1139170Y-467433D01*
Y-471300D01*
G01Y-467433D02*
X1139470Y-466767D01*
X1139970Y-466233D01*
X1140670Y-465967D01*
X1141370Y-466233D01*
X1141870Y-466767D01*
X1142170Y-467567D01*
Y-471300D01*
G01X1147170Y-465967D02*
Y-471300D01*
G01Y-463833D02*
X1146970Y-463700D01*
Y-463433D01*
X1147170Y-463300D01*
X1147370Y-463433D01*
Y-463700D01*
X1147170Y-463833D01*
G01X1155170Y-471300D02*
Y-463300D01*
G01X1106070Y-493133D02*
X1108470D01*
G01X1107170Y-491400D02*
Y-494867D01*
G01X1113370Y-496067D02*
X1116970Y-487800D01*
G01X1121870Y-493133D02*
X1124470D01*
G01X1129270Y-489133D02*
X1129870Y-488333D01*
X1130570Y-487933D01*
X1131370Y-487800D01*
X1132370Y-488067D01*
X1133070Y-488733D01*
X1133270Y-489533D01*
X1133170Y-490334D01*
X1132770Y-491000D01*
X1130770Y-492333D01*
X1129870Y-493267D01*
X1129270Y-494600D01*
X1129070Y-495800D01*
X1133270D01*
G01X1136170D02*
Y-490467D01*
G01Y-491933D02*
X1136470Y-491267D01*
X1136970Y-490733D01*
X1137670Y-490467D01*
X1138370Y-490733D01*
X1138870Y-491267D01*
X1139170Y-491933D01*
Y-495800D01*
G01Y-491933D02*
X1139470Y-491267D01*
X1139970Y-490733D01*
X1140670Y-490467D01*
X1141370Y-490733D01*
X1141870Y-491267D01*
X1142170Y-492067D01*
Y-495800D01*
G01X1147170Y-490467D02*
Y-495800D01*
G01Y-488333D02*
X1146970Y-488200D01*
Y-487933D01*
X1147170Y-487800D01*
X1147370Y-487933D01*
Y-488200D01*
X1147170Y-488333D01*
G01X1155170Y-495800D02*
Y-487800D01*
G01X1105853Y-480933D02*
X1108253D01*
G01X1106953Y-479200D02*
Y-482667D01*
G01X1112753Y-482000D02*
X1113353Y-482933D01*
X1114153Y-483467D01*
X1115053Y-483600D01*
X1115853Y-483467D01*
X1116653Y-482800D01*
X1117153Y-482000D01*
X1117253Y-481200D01*
X1117053Y-480267D01*
X1116353Y-479600D01*
X1115653Y-479333D01*
X1114753D01*
G01X1115653D02*
X1116253Y-478933D01*
X1116753Y-478267D01*
X1116953Y-477467D01*
X1116753Y-476667D01*
X1116253Y-476000D01*
X1115353Y-475600D01*
X1114453Y-475733D01*
X1113553Y-476267D01*
G01X1121153Y-483867D02*
X1124753Y-475600D01*
G01X1129653Y-480933D02*
X1132253D01*
G01X1138953Y-475600D02*
X1138153Y-475867D01*
X1137553Y-476533D01*
X1137153Y-477333D01*
X1136853Y-478400D01*
X1136753Y-479600D01*
X1136853Y-480800D01*
X1137153Y-481867D01*
X1137553Y-482667D01*
X1138153Y-483333D01*
X1138953Y-483600D01*
X1139753Y-483333D01*
X1140353Y-482667D01*
X1140753Y-481867D01*
X1141053Y-480800D01*
X1141153Y-479600D01*
X1141053Y-478400D01*
X1140753Y-477333D01*
X1140353Y-476533D01*
X1139753Y-475867D01*
X1138953Y-475600D01*
G01X1143953Y-483600D02*
Y-478267D01*
G01Y-479733D02*
X1144253Y-479067D01*
X1144753Y-478533D01*
X1145453Y-478267D01*
X1146153Y-478533D01*
X1146653Y-479067D01*
X1146953Y-479733D01*
Y-483600D01*
G01Y-479733D02*
X1147253Y-479067D01*
X1147753Y-478533D01*
X1148453Y-478267D01*
X1149153Y-478533D01*
X1149653Y-479067D01*
X1149953Y-479867D01*
Y-483600D01*
G01X1154953Y-478267D02*
Y-483600D01*
G01Y-476133D02*
X1154753Y-476000D01*
Y-475733D01*
X1154953Y-475600D01*
X1155153Y-475733D01*
Y-476000D01*
X1154953Y-476133D01*
G01X1162953Y-483600D02*
Y-475600D01*
G01X1106070Y-418133D02*
X1108470D01*
G01X1107170Y-416400D02*
Y-419867D01*
G01X1113370Y-421067D02*
X1116970Y-412800D01*
G01X1121870Y-418133D02*
X1124470D01*
G01X1129270Y-414133D02*
X1129870Y-413333D01*
X1130570Y-412933D01*
X1131370Y-412800D01*
X1132370Y-413067D01*
X1133070Y-413733D01*
X1133270Y-414533D01*
X1133170Y-415334D01*
X1132770Y-416000D01*
X1130770Y-417333D01*
X1129870Y-418267D01*
X1129270Y-419600D01*
X1129070Y-420800D01*
X1133270D01*
G01X1136170D02*
Y-415467D01*
G01Y-416933D02*
X1136470Y-416267D01*
X1136970Y-415733D01*
X1137670Y-415467D01*
X1138370Y-415733D01*
X1138870Y-416267D01*
X1139170Y-416933D01*
Y-420800D01*
G01Y-416933D02*
X1139470Y-416267D01*
X1139970Y-415733D01*
X1140670Y-415467D01*
X1141370Y-415733D01*
X1141870Y-416267D01*
X1142170Y-417067D01*
Y-420800D01*
G01X1147170Y-415467D02*
Y-420800D01*
G01Y-413333D02*
X1146970Y-413200D01*
Y-412933D01*
X1147170Y-412800D01*
X1147370Y-412933D01*
Y-413200D01*
X1147170Y-413333D01*
G01X1155170Y-420800D02*
Y-412800D01*
G01X1106070Y-393133D02*
X1108470D01*
G01X1107170Y-391400D02*
Y-394867D01*
G01X1113370Y-396067D02*
X1116970Y-387800D01*
G01X1121870Y-393133D02*
X1124470D01*
G01X1128970Y-394200D02*
X1129570Y-395133D01*
X1130370Y-395667D01*
X1131270Y-395800D01*
X1132070Y-395667D01*
X1132870Y-395000D01*
X1133370Y-394200D01*
X1133470Y-393400D01*
X1133270Y-392467D01*
X1132570Y-391800D01*
X1131870Y-391533D01*
X1130970D01*
G01X1131870D02*
X1132470Y-391133D01*
X1132970Y-390467D01*
X1133170Y-389667D01*
X1132970Y-388867D01*
X1132470Y-388200D01*
X1131570Y-387800D01*
X1130670Y-387933D01*
X1129770Y-388467D01*
G01X1136170Y-395800D02*
Y-390467D01*
G01Y-391933D02*
X1136470Y-391267D01*
X1136970Y-390733D01*
X1137670Y-390467D01*
X1138370Y-390733D01*
X1138870Y-391267D01*
X1139170Y-391933D01*
Y-395800D01*
G01Y-391933D02*
X1139470Y-391267D01*
X1139970Y-390733D01*
X1140670Y-390467D01*
X1141370Y-390733D01*
X1141870Y-391267D01*
X1142170Y-392067D01*
Y-395800D01*
G01X1147170Y-390467D02*
Y-395800D01*
G01Y-388333D02*
X1146970Y-388200D01*
Y-387933D01*
X1147170Y-387800D01*
X1147370Y-387933D01*
Y-388200D01*
X1147170Y-388333D01*
G01X1155170Y-395800D02*
Y-387800D01*
G01X1106070Y-405633D02*
X1108470D01*
G01X1107170Y-403900D02*
Y-407367D01*
G01X1113270Y-401633D02*
X1113870Y-400833D01*
X1114570Y-400433D01*
X1115370Y-400300D01*
X1116370Y-400567D01*
X1117070Y-401233D01*
X1117270Y-402033D01*
X1117170Y-402834D01*
X1116770Y-403500D01*
X1114770Y-404833D01*
X1113870Y-405767D01*
X1113270Y-407100D01*
X1113070Y-408300D01*
X1117270D01*
G01X1121370Y-408567D02*
X1124970Y-400300D01*
G01X1129870Y-405633D02*
X1132470D01*
G01X1140370Y-408300D02*
Y-400300D01*
X1136670Y-406033D01*
X1141670D01*
G01X1144170Y-408300D02*
Y-402967D01*
G01Y-404433D02*
X1144470Y-403767D01*
X1144970Y-403233D01*
X1145670Y-402967D01*
X1146370Y-403233D01*
X1146870Y-403767D01*
X1147170Y-404433D01*
Y-408300D01*
G01Y-404433D02*
X1147470Y-403767D01*
X1147970Y-403233D01*
X1148670Y-402967D01*
X1149370Y-403233D01*
X1149870Y-403767D01*
X1150170Y-404567D01*
Y-408300D01*
G01X1155170Y-402967D02*
Y-408300D01*
G01Y-400833D02*
X1154970Y-400700D01*
Y-400433D01*
X1155170Y-400300D01*
X1155370Y-400433D01*
Y-400700D01*
X1155170Y-400833D01*
G01X1163170Y-408300D02*
Y-400300D01*
G01X1106070Y-430133D02*
X1108470D01*
G01X1107170Y-428400D02*
Y-431867D01*
G01X1115170Y-432800D02*
Y-424800D01*
X1113970Y-426400D01*
G01Y-432800D02*
X1116370D01*
G01X1121370Y-433067D02*
X1124970Y-424800D01*
G01X1129870Y-430133D02*
X1132470D01*
G01X1136970Y-431200D02*
X1137570Y-432133D01*
X1138370Y-432667D01*
X1139270Y-432800D01*
X1140070Y-432667D01*
X1140870Y-432000D01*
X1141370Y-431200D01*
X1141470Y-430400D01*
X1141270Y-429467D01*
X1140570Y-428800D01*
X1139870Y-428533D01*
X1138970D01*
G01X1139870D02*
X1140470Y-428133D01*
X1140970Y-427467D01*
X1141170Y-426667D01*
X1140970Y-425867D01*
X1140470Y-425200D01*
X1139570Y-424800D01*
X1138670Y-424933D01*
X1137770Y-425467D01*
G01X1144170Y-432800D02*
Y-427467D01*
G01Y-428933D02*
X1144470Y-428267D01*
X1144970Y-427733D01*
X1145670Y-427467D01*
X1146370Y-427733D01*
X1146870Y-428267D01*
X1147170Y-428933D01*
Y-432800D01*
G01Y-428933D02*
X1147470Y-428267D01*
X1147970Y-427733D01*
X1148670Y-427467D01*
X1149370Y-427733D01*
X1149870Y-428267D01*
X1150170Y-429067D01*
Y-432800D01*
G01X1155170Y-427467D02*
Y-432800D01*
G01Y-425333D02*
X1154970Y-425200D01*
Y-424933D01*
X1155170Y-424800D01*
X1155370Y-424933D01*
Y-425200D01*
X1155170Y-425333D01*
G01X1163170Y-432800D02*
Y-424800D01*
G01X1107233Y-373000D02*
Y-381000D01*
G01X1104933Y-373000D02*
X1109533D01*
G01X1115233Y-381000D02*
X1114633Y-380867D01*
X1114033Y-380333D01*
X1113633Y-379400D01*
X1113433Y-378333D01*
X1113633Y-377267D01*
X1114033Y-376333D01*
X1114633Y-375800D01*
X1115233Y-375667D01*
X1115833Y-375800D01*
X1116433Y-376333D01*
X1116833Y-377267D01*
X1116933Y-378333D01*
X1116833Y-379400D01*
X1116433Y-380333D01*
X1115833Y-380867D01*
X1115233Y-381000D01*
G01X1123233D02*
Y-373000D01*
G01X1129733Y-377400D02*
X1132933D01*
X1132633Y-376467D01*
X1132133Y-375933D01*
X1131433Y-375667D01*
X1130733Y-375800D01*
X1130133Y-376200D01*
X1129733Y-377133D01*
X1129533Y-377934D01*
Y-378733D01*
X1129733Y-379533D01*
X1130233Y-380333D01*
X1130833Y-380867D01*
X1131533Y-381000D01*
X1132233Y-380733D01*
X1132933Y-379934D01*
G01X1137833Y-381000D02*
Y-375667D01*
G01Y-376733D02*
X1138333Y-376200D01*
X1138833Y-375800D01*
X1139533Y-375667D01*
X1140033Y-375800D01*
X1140633Y-376200D01*
G01X1149033Y-381000D02*
Y-375667D01*
G01Y-376600D02*
X1148633Y-376067D01*
X1148033Y-375800D01*
X1147333Y-375667D01*
X1146633Y-375933D01*
X1146033Y-376467D01*
X1145633Y-377267D01*
X1145433Y-378333D01*
X1145633Y-379400D01*
X1146033Y-380200D01*
X1146633Y-380733D01*
X1147333Y-381000D01*
X1148033Y-380867D01*
X1148633Y-380467D01*
X1149033Y-379934D01*
G01X1153533Y-381000D02*
Y-375667D01*
G01Y-377000D02*
X1153933Y-376333D01*
X1154533Y-375800D01*
X1155333Y-375667D01*
X1156033Y-375800D01*
X1156633Y-376333D01*
X1156933Y-377267D01*
Y-381000D01*
G01X1164833Y-376333D02*
X1164133Y-375800D01*
X1163533Y-375667D01*
X1162733Y-375933D01*
X1162133Y-376467D01*
X1161733Y-377400D01*
X1161633Y-378333D01*
X1161733Y-379267D01*
X1162133Y-380067D01*
X1162733Y-380733D01*
X1163533Y-381000D01*
X1164233Y-380733D01*
X1164833Y-380200D01*
G01X1169733Y-377400D02*
X1172933D01*
X1172633Y-376467D01*
X1172133Y-375933D01*
X1171433Y-375667D01*
X1170733Y-375800D01*
X1170133Y-376200D01*
X1169733Y-377133D01*
X1169533Y-377934D01*
Y-378733D01*
X1169733Y-379533D01*
X1170233Y-380333D01*
X1170833Y-380867D01*
X1171533Y-381000D01*
X1172233Y-380733D01*
X1172933Y-379934D01*
G01X1123333Y-256700D02*
Y-256600D01*
G01X1324833Y172700D02*
X1327333Y164700D01*
X1329833Y172700D01*
G01X1335333Y164700D02*
Y172700D01*
X1334133Y171100D01*
G01Y164700D02*
X1336533D01*
G01X1343333Y164433D02*
X1343133Y164567D01*
Y164833D01*
X1343333Y164967D01*
X1343533Y164833D01*
Y164567D01*
X1343333Y164433D01*
G01X1351333Y172700D02*
X1350533Y172433D01*
X1349933Y171767D01*
X1349533Y170967D01*
X1349233Y169900D01*
X1349133Y168700D01*
X1349233Y167500D01*
X1349533Y166433D01*
X1349933Y165633D01*
X1350533Y164967D01*
X1351333Y164700D01*
X1352133Y164967D01*
X1352733Y165633D01*
X1353133Y166433D01*
X1353433Y167500D01*
X1353533Y168700D01*
X1353433Y169900D01*
X1353133Y170967D01*
X1352733Y171767D01*
X1352133Y172433D01*
X1351333Y172700D01*
G01X1356633Y161700D02*
Y-707100D01*
G01X1099533Y-536000D02*
X1183333D01*
Y-523500D01*
X503833D01*
G01Y-536000D02*
X1099533D01*
Y-368500D01*
X1183333D01*
Y-386000D01*
G01X503833Y-368500D02*
Y-536000D01*
G01Y-511000D02*
X531833D01*
G01X503833Y-498500D02*
Y-511000D01*
G01Y-498500D02*
Y-511000D01*
G01X531833Y-536000D02*
Y-411000D01*
G01X503833Y-448500D02*
X531833D01*
G01X503833Y-486000D02*
X531833D01*
G01X503833Y-473500D02*
Y-486000D01*
G01Y-498500D02*
X531833D01*
G01X503833Y-473500D02*
X531833D01*
G01X503833Y-461000D02*
Y-473500D01*
G01Y-461000D02*
X531833D01*
G01X503833Y-448500D02*
Y-461000D01*
G01D02*
X531833D01*
G01X503833Y-448500D02*
Y-461000D01*
G01Y-386000D02*
X1183333D01*
Y-398500D01*
G01X503833Y-423500D02*
X531833D01*
G01X503833Y-436000D02*
X531833D01*
G01X503833Y-411000D02*
Y-423500D01*
G01X531833Y-411000D02*
Y-398500D01*
G01X503833Y-411000D02*
X531833D01*
G01X503833Y-398500D02*
Y-411000D01*
G01X531833Y-398500D02*
Y-386000D01*
G01X503833Y-398500D02*
X531833D01*
G01X503833Y-386000D02*
Y-398500D01*
G01Y-386000D02*
Y-368500D01*
G01X1156833Y-386000D02*
X503833D01*
G01X531833D02*
Y-368500D01*
G01Y-398500D02*
X645833D01*
G01X512833Y-368500D02*
X1099533D01*
G01X1159983D02*
X503833D01*
G01D02*
X512833D01*
G01X645833Y-536000D02*
Y-385500D01*
G01X1159983Y-511000D02*
X645833D01*
G01Y-486000D02*
X1183333D01*
Y-498500D01*
G01X645833Y-448500D02*
X1183333D01*
Y-461000D01*
G01X1159983Y-498500D02*
X645833D01*
G01X1159983Y-473500D02*
X645833D01*
G01X1159983Y-461000D02*
X645833D01*
G01X1159983D02*
X645833D01*
G01Y-423500D02*
X1183333D01*
Y-436000D01*
G01X645833Y-398500D02*
Y-386000D01*
G01X1159983Y-411000D02*
X645833D01*
G01X1159983Y-436000D02*
X645833D01*
G01Y-386000D02*
Y-368500D01*
G01X1159983Y-398500D02*
X645833D01*
G01X1068483Y-511000D02*
X1183333D01*
Y-523500D01*
G01X1068483Y-498500D02*
X1183333D01*
Y-511000D01*
G01X1068483Y-473500D02*
X1183333D01*
Y-486000D01*
G01X1068483Y-461000D02*
X1183333D01*
Y-473500D01*
G01X1068483Y-461000D02*
X1159983D01*
G01X1068483Y-436000D02*
X1183333D01*
Y-448500D01*
G01X1068483Y-411000D02*
X1183333D01*
Y-423500D01*
G01X1068483Y-398500D02*
X1183333D01*
Y-411000D01*
G01X1099633Y-546100D02*
X1099533Y-546000D01*
M02*
